FILE_TYPE = MACRO_DRAWING;
SET COLOR_WIRE YELLOW;
SET COLOR_PROP ORANGE;
SET COLOR_DOT WHITE;
SET COLOR_ARC YELLOW;
SET COLOR_BODY GREEN;
SET COLOR_NOTE PURPLE;
SET PROP_DISPLAY VALUE;
SET PAGE_NUMBER P58;
FORCEADD OFFPAGE..2
R 2
(-1675 -200);
FORCEPROP 2 LAST $XR1 113 
J 0
(-2050 -200);
DISPLAY 0.638298 (-2050 -200);
PAINT MONO (-2050 -200);
FORCEPROP 2 LAST $XR0 112 
J 0
(-1930 -200);
DISPLAY 0.638298 (-1930 -200);
PAINT MONO (-1930 -200);
FORCEPROP 2 LAST CDS_LIB standard
J 0
(-1675 -200);
PAINT MONO (-1675 -200);
DISPLAY INVISIBLE (-1675 -200);
FORCEPROP 1 LAST OFFPAGE TRUE
J 2
(-2000 -325);
DISPLAY 0.872340 (-2000 -325);
DISPLAY INVISIBLE (-2000 -325);
FORCEPROP 1 LAST COMMENT_BODY TRUE
J 2
(-1630 -295);
DISPLAY 0.872340 (-1630 -295);
PAINT GREEN (-1630 -295);
DISPLAY INVISIBLE (-1630 -295);
FORCEPROP 2 LAST PATH I1
J 0
(-1625 -125);
DISPLAY 1.021277 (-1625 -125);
DISPLAY INVISIBLE (-1625 -125);
FORCEADD TAP..1
R 2
(-650 -75);
FORCEPROP 3 LASTPIN (-600 -75) SIG_NAME M_H_CPU1_SB_CB<1>
J 0
(-590 -65);
DISPLAY 0.659574 (-590 -65);
PAINT MONO (-590 -65);
DISPLAY INVISIBLE (-590 -65);
FORCEPROP 1 LASTPIN (-600 -75) BN 1
J 2
(-588 -67);
DISPLAY 0.680851 (-588 -67);
PAINT GREEN (-588 -67);
FORCEPROP 2 LAST CDS_LIB standard
J 0
(-650 -75);
DISPLAY INVISIBLE (-650 -75);
FORCEPROP 1 LAST BODY_TYPE PLUMBING
J 2
(-650 -25);
DISPLAY 0.872340 (-650 -25);
PAINT GREEN (-650 -25);
DISPLAY INVISIBLE (-650 -25);
FORCEPROP 1 LAST HDL_TAP TRUE
J 2
(-975 -200);
DISPLAY 0.872340 (-975 -200);
DISPLAY INVISIBLE (-975 -200);
FORCEPROP 1 LAST PATH I10
J 2
(-648 -75);
DISPLAY 0.872340 (-648 -75);
PAINT GREEN (-648 -75);
DISPLAY INVISIBLE (-648 -75);
FORCEADD TAP..1
(2775 725);
FORCEPROP 3 LASTPIN (2725 725) SIG_NAME M_H_CPU1_SB_CA<0>
J 0
(2735 735);
DISPLAY 0.659574 (2735 735);
PAINT MONO (2735 735);
DISPLAY INVISIBLE (2735 735);
FORCEPROP 1 LASTPIN (2725 725) BN 0
J 0
(2713 733);
DISPLAY 0.680851 (2713 733);
PAINT GREEN (2713 733);
FORCEPROP 2 LAST CDS_LIB standard
J 0
(2775 725);
DISPLAY INVISIBLE (2775 725);
FORCEPROP 1 LAST BODY_TYPE PLUMBING
J 0
(2775 775);
DISPLAY 0.872340 (2775 775);
PAINT GREEN (2775 775);
DISPLAY INVISIBLE (2775 775);
FORCEPROP 1 LAST HDL_TAP TRUE
J 0
(3100 600);
DISPLAY 0.872340 (3100 600);
DISPLAY INVISIBLE (3100 600);
FORCEPROP 1 LAST PATH I100
J 0
(2773 725);
DISPLAY 0.872340 (2773 725);
PAINT GREEN (2773 725);
DISPLAY INVISIBLE (2773 725);
FORCEADD TAP..1
(2775 825);
FORCEPROP 3 LASTPIN (2725 825) SIG_NAME M_H_CPU1_SB_CA<2>
J 0
(2735 835);
DISPLAY 0.659574 (2735 835);
PAINT MONO (2735 835);
DISPLAY INVISIBLE (2735 835);
FORCEPROP 1 LASTPIN (2725 825) BN 2
J 0
(2713 833);
DISPLAY 0.680851 (2713 833);
PAINT GREEN (2713 833);
FORCEPROP 2 LAST CDS_LIB standard
J 0
(2775 825);
DISPLAY INVISIBLE (2775 825);
FORCEPROP 1 LAST BODY_TYPE PLUMBING
J 0
(2775 875);
DISPLAY 0.872340 (2775 875);
PAINT GREEN (2775 875);
DISPLAY INVISIBLE (2775 875);
FORCEPROP 1 LAST HDL_TAP TRUE
J 0
(3100 700);
DISPLAY 0.872340 (3100 700);
DISPLAY INVISIBLE (3100 700);
FORCEPROP 1 LAST PATH I101
J 0
(2773 825);
DISPLAY 0.872340 (2773 825);
PAINT GREEN (2773 825);
DISPLAY INVISIBLE (2773 825);
FORCEADD TAP..1
(2775 775);
FORCEPROP 3 LASTPIN (2725 775) SIG_NAME M_H_CPU1_SB_CA<1>
J 0
(2735 785);
DISPLAY 0.659574 (2735 785);
PAINT MONO (2735 785);
DISPLAY INVISIBLE (2735 785);
FORCEPROP 1 LASTPIN (2725 775) BN 1
J 0
(2713 783);
DISPLAY 0.680851 (2713 783);
PAINT GREEN (2713 783);
FORCEPROP 2 LAST CDS_LIB standard
J 0
(2775 775);
DISPLAY INVISIBLE (2775 775);
FORCEPROP 1 LAST BODY_TYPE PLUMBING
J 0
(2775 825);
DISPLAY 0.872340 (2775 825);
PAINT GREEN (2775 825);
DISPLAY INVISIBLE (2775 825);
FORCEPROP 1 LAST HDL_TAP TRUE
J 0
(3100 650);
DISPLAY 0.872340 (3100 650);
DISPLAY INVISIBLE (3100 650);
FORCEPROP 1 LAST PATH I102
J 0
(2773 775);
DISPLAY 0.872340 (2773 775);
PAINT GREEN (2773 775);
DISPLAY INVISIBLE (2773 775);
FORCEADD TAP..1
(2775 925);
FORCEPROP 3 LASTPIN (2725 925) SIG_NAME M_H_CPU1_SB_CA<4>
J 0
(2735 935);
DISPLAY 0.659574 (2735 935);
PAINT MONO (2735 935);
DISPLAY INVISIBLE (2735 935);
FORCEPROP 1 LASTPIN (2725 925) BN 4
J 0
(2713 933);
DISPLAY 0.680851 (2713 933);
PAINT GREEN (2713 933);
FORCEPROP 2 LAST CDS_LIB standard
J 0
(2775 925);
DISPLAY INVISIBLE (2775 925);
FORCEPROP 1 LAST BODY_TYPE PLUMBING
J 0
(2775 975);
DISPLAY 0.872340 (2775 975);
PAINT GREEN (2775 975);
DISPLAY INVISIBLE (2775 975);
FORCEPROP 1 LAST HDL_TAP TRUE
J 0
(3100 800);
DISPLAY 0.872340 (3100 800);
DISPLAY INVISIBLE (3100 800);
FORCEPROP 1 LAST PATH I103
J 0
(2773 925);
DISPLAY 0.872340 (2773 925);
PAINT GREEN (2773 925);
DISPLAY INVISIBLE (2773 925);
FORCEADD TAP..1
(2775 1025);
FORCEPROP 3 LASTPIN (2725 1025) SIG_NAME M_H_CPU1_SB_CA<6>
J 0
(2735 1035);
DISPLAY 0.659574 (2735 1035);
PAINT MONO (2735 1035);
DISPLAY INVISIBLE (2735 1035);
FORCEPROP 1 LASTPIN (2725 1025) BN 6
J 0
(2713 1033);
DISPLAY 0.680851 (2713 1033);
PAINT GREEN (2713 1033);
FORCEPROP 2 LAST CDS_LIB standard
J 0
(2775 1025);
DISPLAY INVISIBLE (2775 1025);
FORCEPROP 1 LAST BODY_TYPE PLUMBING
J 0
(2775 1075);
DISPLAY 0.872340 (2775 1075);
PAINT GREEN (2775 1075);
DISPLAY INVISIBLE (2775 1075);
FORCEPROP 1 LAST HDL_TAP TRUE
J 0
(3100 900);
DISPLAY 0.872340 (3100 900);
DISPLAY INVISIBLE (3100 900);
FORCEPROP 1 LAST PATH I104
J 0
(2773 1025);
DISPLAY 0.872340 (2773 1025);
PAINT GREEN (2773 1025);
DISPLAY INVISIBLE (2773 1025);
FORCEADD TAP..1
(2775 875);
FORCEPROP 3 LASTPIN (2725 875) SIG_NAME M_H_CPU1_SB_CA<3>
J 0
(2735 885);
DISPLAY 0.659574 (2735 885);
PAINT MONO (2735 885);
DISPLAY INVISIBLE (2735 885);
FORCEPROP 1 LASTPIN (2725 875) BN 3
J 0
(2713 883);
DISPLAY 0.680851 (2713 883);
PAINT GREEN (2713 883);
FORCEPROP 2 LAST CDS_LIB standard
J 0
(2775 875);
DISPLAY INVISIBLE (2775 875);
FORCEPROP 1 LAST BODY_TYPE PLUMBING
J 0
(2775 925);
DISPLAY 0.872340 (2775 925);
PAINT GREEN (2775 925);
DISPLAY INVISIBLE (2775 925);
FORCEPROP 1 LAST HDL_TAP TRUE
J 0
(3100 750);
DISPLAY 0.872340 (3100 750);
DISPLAY INVISIBLE (3100 750);
FORCEPROP 1 LAST PATH I105
J 0
(2773 875);
DISPLAY 0.872340 (2773 875);
PAINT GREEN (2773 875);
DISPLAY INVISIBLE (2773 875);
FORCEADD TAP..1
(2775 975);
FORCEPROP 3 LASTPIN (2725 975) SIG_NAME M_H_CPU1_SB_CA<5>
J 0
(2735 985);
DISPLAY 0.659574 (2735 985);
PAINT MONO (2735 985);
DISPLAY INVISIBLE (2735 985);
FORCEPROP 1 LASTPIN (2725 975) BN 5
J 0
(2713 983);
DISPLAY 0.680851 (2713 983);
PAINT GREEN (2713 983);
FORCEPROP 2 LAST CDS_LIB standard
J 0
(2775 975);
DISPLAY INVISIBLE (2775 975);
FORCEPROP 1 LAST BODY_TYPE PLUMBING
J 0
(2775 1025);
DISPLAY 0.872340 (2775 1025);
PAINT GREEN (2775 1025);
DISPLAY INVISIBLE (2775 1025);
FORCEPROP 1 LAST HDL_TAP TRUE
J 0
(3100 850);
DISPLAY 0.872340 (3100 850);
DISPLAY INVISIBLE (3100 850);
FORCEPROP 1 LAST PATH I106
J 0
(2773 975);
DISPLAY 0.872340 (2773 975);
PAINT GREEN (2773 975);
DISPLAY INVISIBLE (2773 975);
FORCEADD TAP..1
(2775 1225);
FORCEPROP 3 LASTPIN (2725 1225) SIG_NAME M_H_CPU1_SA_CA<0>
J 0
(2735 1235);
DISPLAY 0.659574 (2735 1235);
PAINT MONO (2735 1235);
DISPLAY INVISIBLE (2735 1235);
FORCEPROP 1 LASTPIN (2725 1225) BN 0
J 0
(2713 1233);
DISPLAY 0.680851 (2713 1233);
PAINT GREEN (2713 1233);
FORCEPROP 2 LAST CDS_LIB standard
J 0
(2775 1225);
DISPLAY INVISIBLE (2775 1225);
FORCEPROP 1 LAST BODY_TYPE PLUMBING
J 0
(2775 1275);
DISPLAY 0.872340 (2775 1275);
PAINT GREEN (2775 1275);
DISPLAY INVISIBLE (2775 1275);
FORCEPROP 1 LAST HDL_TAP TRUE
J 0
(3100 1100);
DISPLAY 0.872340 (3100 1100);
DISPLAY INVISIBLE (3100 1100);
FORCEPROP 1 LAST PATH I107
J 0
(2773 1225);
DISPLAY 0.872340 (2773 1225);
PAINT GREEN (2773 1225);
DISPLAY INVISIBLE (2773 1225);
FORCEADD TAP..1
(2775 1325);
FORCEPROP 3 LASTPIN (2725 1325) SIG_NAME M_H_CPU1_SA_CA<2>
J 0
(2735 1335);
DISPLAY 0.659574 (2735 1335);
PAINT MONO (2735 1335);
DISPLAY INVISIBLE (2735 1335);
FORCEPROP 1 LASTPIN (2725 1325) BN 2
J 0
(2713 1333);
DISPLAY 0.680851 (2713 1333);
PAINT GREEN (2713 1333);
FORCEPROP 2 LAST CDS_LIB standard
J 0
(2775 1325);
DISPLAY INVISIBLE (2775 1325);
FORCEPROP 1 LAST BODY_TYPE PLUMBING
J 0
(2775 1375);
DISPLAY 0.872340 (2775 1375);
PAINT GREEN (2775 1375);
DISPLAY INVISIBLE (2775 1375);
FORCEPROP 1 LAST HDL_TAP TRUE
J 0
(3100 1200);
DISPLAY 0.872340 (3100 1200);
DISPLAY INVISIBLE (3100 1200);
FORCEPROP 1 LAST PATH I108
J 0
(2773 1325);
DISPLAY 0.872340 (2773 1325);
PAINT GREEN (2773 1325);
DISPLAY INVISIBLE (2773 1325);
FORCEADD TAP..1
(2775 1275);
FORCEPROP 3 LASTPIN (2725 1275) SIG_NAME M_H_CPU1_SA_CA<1>
J 0
(2735 1285);
DISPLAY 0.659574 (2735 1285);
PAINT MONO (2735 1285);
DISPLAY INVISIBLE (2735 1285);
FORCEPROP 1 LASTPIN (2725 1275) BN 1
J 0
(2713 1283);
DISPLAY 0.680851 (2713 1283);
PAINT GREEN (2713 1283);
FORCEPROP 2 LAST CDS_LIB standard
J 0
(2775 1275);
DISPLAY INVISIBLE (2775 1275);
FORCEPROP 1 LAST BODY_TYPE PLUMBING
J 0
(2775 1325);
DISPLAY 0.872340 (2775 1325);
PAINT GREEN (2775 1325);
DISPLAY INVISIBLE (2775 1325);
FORCEPROP 1 LAST HDL_TAP TRUE
J 0
(3100 1150);
DISPLAY 0.872340 (3100 1150);
DISPLAY INVISIBLE (3100 1150);
FORCEPROP 1 LAST PATH I109
J 0
(2773 1275);
DISPLAY 0.872340 (2773 1275);
PAINT GREEN (2773 1275);
DISPLAY INVISIBLE (2773 1275);
FORCEADD TAP..1
R 2
(-650 -125);
FORCEPROP 3 LASTPIN (-600 -125) SIG_NAME M_H_CPU1_SB_CB<0>
J 0
(-590 -115);
DISPLAY 0.659574 (-590 -115);
PAINT MONO (-590 -115);
DISPLAY INVISIBLE (-590 -115);
FORCEPROP 1 LASTPIN (-600 -125) BN 0
J 2
(-588 -117);
DISPLAY 0.680851 (-588 -117);
PAINT GREEN (-588 -117);
FORCEPROP 2 LAST CDS_LIB standard
J 0
(-650 -125);
DISPLAY INVISIBLE (-650 -125);
FORCEPROP 1 LAST BODY_TYPE PLUMBING
J 2
(-650 -75);
DISPLAY 0.872340 (-650 -75);
PAINT GREEN (-650 -75);
DISPLAY INVISIBLE (-650 -75);
FORCEPROP 1 LAST HDL_TAP TRUE
J 2
(-975 -250);
DISPLAY 0.872340 (-975 -250);
DISPLAY INVISIBLE (-975 -250);
FORCEPROP 1 LAST PATH I11
J 2
(-648 -125);
DISPLAY 0.872340 (-648 -125);
PAINT GREEN (-648 -125);
DISPLAY INVISIBLE (-648 -125);
FORCEADD OFFPAGE..4
(3875 -375);
FORCEPROP 2 LAST $XR1 113 
J 0
(4181 -375);
DISPLAY 0.638298 (4181 -375);
PAINT MONO (4181 -375);
FORCEPROP 2 LAST $XR0 112 
J 0
(4061 -375);
DISPLAY 0.638298 (4061 -375);
PAINT MONO (4061 -375);
FORCEPROP 2 LAST CDS_LIB standard
J 0
(3875 -375);
PAINT MONO (3875 -375);
DISPLAY INVISIBLE (3875 -375);
FORCEPROP 1 LAST OFFPAGE TRUE
J 0
(4200 -500);
DISPLAY 1.170213 (4200 -500);
PAINT GREEN (4200 -500);
DISPLAY INVISIBLE (4200 -500);
FORCEPROP 1 LAST COMMENT_BODY TRUE
J 0
(3850 -475);
DISPLAY 1.170213 (3850 -475);
PAINT GREEN (3850 -475);
DISPLAY INVISIBLE (3850 -475);
FORCEPROP 2 LAST PATH I110
J 0
(4050 -300);
DISPLAY 1.021277 (4050 -300);
DISPLAY INVISIBLE (4050 -300);
FORCEADD OFFPAGE..4
(3875 -275);
FORCEPROP 2 LAST $XR0 112 
J 0
(4061 -275);
DISPLAY 0.638298 (4061 -275);
PAINT MONO (4061 -275);
FORCEPROP 2 LAST CDS_LIB standard
J 0
(3875 -275);
PAINT MONO (3875 -275);
DISPLAY INVISIBLE (3875 -275);
FORCEPROP 1 LAST OFFPAGE TRUE
J 0
(4200 -400);
DISPLAY 1.170213 (4200 -400);
PAINT GREEN (4200 -400);
DISPLAY INVISIBLE (4200 -400);
FORCEPROP 1 LAST COMMENT_BODY TRUE
J 0
(3850 -375);
DISPLAY 1.170213 (3850 -375);
PAINT GREEN (3850 -375);
DISPLAY INVISIBLE (3850 -375);
FORCEPROP 2 LAST PATH I111
J 0
(4050 -200);
DISPLAY 1.021277 (4050 -200);
DISPLAY INVISIBLE (4050 -200);
FORCEADD OFFPAGE..4
(3875 -225);
FORCEPROP 2 LAST $XR0 113 
J 0
(4061 -225);
DISPLAY 0.638298 (4061 -225);
PAINT MONO (4061 -225);
FORCEPROP 2 LAST CDS_LIB standard
J 0
(3875 -225);
PAINT MONO (3875 -225);
DISPLAY INVISIBLE (3875 -225);
FORCEPROP 1 LAST OFFPAGE TRUE
J 0
(4200 -350);
DISPLAY 1.170213 (4200 -350);
PAINT GREEN (4200 -350);
DISPLAY INVISIBLE (4200 -350);
FORCEPROP 1 LAST COMMENT_BODY TRUE
J 0
(3850 -325);
DISPLAY 1.170213 (3850 -325);
PAINT GREEN (3850 -325);
DISPLAY INVISIBLE (3850 -325);
FORCEPROP 2 LAST PATH I112
J 0
(4050 -150);
DISPLAY 1.021277 (4050 -150);
DISPLAY INVISIBLE (4050 -150);
FORCEADD OFFPAGE..4
(3875 -125);
FORCEPROP 2 LAST $XR0 112 
J 0
(4061 -125);
DISPLAY 0.638298 (4061 -125);
PAINT MONO (4061 -125);
FORCEPROP 2 LAST CDS_LIB standard
J 0
(3875 -125);
PAINT MONO (3875 -125);
DISPLAY INVISIBLE (3875 -125);
FORCEPROP 1 LAST OFFPAGE TRUE
J 0
(4200 -250);
DISPLAY 1.170213 (4200 -250);
PAINT GREEN (4200 -250);
DISPLAY INVISIBLE (4200 -250);
FORCEPROP 1 LAST COMMENT_BODY TRUE
J 0
(3850 -225);
DISPLAY 1.170213 (3850 -225);
PAINT GREEN (3850 -225);
DISPLAY INVISIBLE (3850 -225);
FORCEPROP 2 LAST PATH I113
J 0
(4050 -50);
DISPLAY 1.021277 (4050 -50);
DISPLAY INVISIBLE (4050 -50);
FORCEADD OFFPAGE..4
(3875 -75);
FORCEPROP 2 LAST $XR0 113 
J 0
(4061 -75);
DISPLAY 0.638298 (4061 -75);
PAINT MONO (4061 -75);
FORCEPROP 2 LAST CDS_LIB standard
J 0
(3875 -75);
PAINT MONO (3875 -75);
DISPLAY INVISIBLE (3875 -75);
FORCEPROP 1 LAST OFFPAGE TRUE
J 0
(4200 -200);
DISPLAY 1.170213 (4200 -200);
PAINT GREEN (4200 -200);
DISPLAY INVISIBLE (4200 -200);
FORCEPROP 1 LAST COMMENT_BODY TRUE
J 0
(3850 -175);
DISPLAY 1.170213 (3850 -175);
PAINT GREEN (3850 -175);
DISPLAY INVISIBLE (3850 -175);
FORCEPROP 2 LAST PATH I114
J 0
(4050 0);
DISPLAY 1.021277 (4050 0);
DISPLAY INVISIBLE (4050 0);
FORCEADD OFFPAGE..2
(3875 250);
FORCEPROP 2 LAST $XR1 113 
J 0
(4184 250);
DISPLAY 0.638298 (4184 250);
PAINT MONO (4184 250);
FORCEPROP 2 LAST $XR0 112 
J 0
(4064 250);
DISPLAY 0.638298 (4064 250);
PAINT MONO (4064 250);
FORCEPROP 2 LAST CDS_LIB standard
J 0
(3875 250);
PAINT MONO (3875 250);
DISPLAY INVISIBLE (3875 250);
FORCEPROP 1 LAST OFFPAGE TRUE
J 0
(4200 125);
DISPLAY 1.170213 (4200 125);
PAINT GREEN (4200 125);
DISPLAY INVISIBLE (4200 125);
FORCEPROP 1 LAST COMMENT_BODY TRUE
J 0
(3830 155);
DISPLAY 1.170213 (3830 155);
PAINT GREEN (3830 155);
DISPLAY INVISIBLE (3830 155);
FORCEPROP 2 LAST PATH I115
J 0
(4050 325);
DISPLAY 1.021277 (4050 325);
DISPLAY INVISIBLE (4050 325);
FORCEADD OFFPAGE..2
(3875 550);
FORCEPROP 2 LAST $XR1 113 
J 0
(4184 550);
DISPLAY 0.638298 (4184 550);
PAINT MONO (4184 550);
FORCEPROP 2 LAST $XR0 112 
J 0
(4064 550);
DISPLAY 0.638298 (4064 550);
PAINT MONO (4064 550);
FORCEPROP 2 LAST CDS_LIB standard
J 0
(3875 550);
PAINT MONO (3875 550);
DISPLAY INVISIBLE (3875 550);
FORCEPROP 1 LAST OFFPAGE TRUE
J 0
(4200 425);
DISPLAY 1.170213 (4200 425);
PAINT GREEN (4200 425);
DISPLAY INVISIBLE (4200 425);
FORCEPROP 1 LAST COMMENT_BODY TRUE
J 0
(3830 455);
DISPLAY 1.170213 (3830 455);
PAINT GREEN (3830 455);
DISPLAY INVISIBLE (3830 455);
FORCEPROP 2 LAST PATH I116
J 0
(4050 625);
DISPLAY 1.021277 (4050 625);
DISPLAY INVISIBLE (4050 625);
FORCEADD OFFPAGE..2
(3875 675);
FORCEPROP 2 LAST $XR1 113 
J 0
(4184 675);
DISPLAY 0.638298 (4184 675);
PAINT MONO (4184 675);
FORCEPROP 2 LAST $XR0 112 
J 0
(4064 675);
DISPLAY 0.638298 (4064 675);
PAINT MONO (4064 675);
FORCEPROP 2 LAST CDS_LIB standard
J 0
(3875 675);
PAINT MONO (3875 675);
DISPLAY INVISIBLE (3875 675);
FORCEPROP 1 LAST OFFPAGE TRUE
J 0
(4200 550);
DISPLAY 1.170213 (4200 550);
PAINT GREEN (4200 550);
DISPLAY INVISIBLE (4200 550);
FORCEPROP 1 LAST COMMENT_BODY TRUE
J 0
(3830 580);
DISPLAY 1.170213 (3830 580);
PAINT GREEN (3830 580);
DISPLAY INVISIBLE (3830 580);
FORCEPROP 2 LAST PATH I117
J 0
(4050 750);
DISPLAY 1.021277 (4050 750);
DISPLAY INVISIBLE (4050 750);
FORCEADD OFFPAGE..3
(3875 1050);
FORCEPROP 2 LAST $XR1 113 
J 0
(4209 1050);
DISPLAY 0.638298 (4209 1050);
PAINT MONO (4209 1050);
FORCEPROP 2 LAST $XR0 112 
J 0
(4089 1050);
DISPLAY 0.638298 (4089 1050);
PAINT MONO (4089 1050);
FORCEPROP 2 LAST CDS_LIB standard
J 2
(3875 1050);
DISPLAY INVISIBLE (3875 1050);
FORCEPROP 1 LAST OFFPAGE TRUE
J 0
(4200 925);
DISPLAY 0.872340 (4200 925);
DISPLAY INVISIBLE (4200 925);
FORCEPROP 1 LAST COMMENT_BODY TRUE
J 0
(3825 950);
DISPLAY 0.872340 (3825 950);
PAINT GREEN (3825 950);
DISPLAY INVISIBLE (3825 950);
FORCEPROP 2 LAST PATH I118
J 0
(4075 1125);
DISPLAY 1.021277 (4075 1125);
DISPLAY INVISIBLE (4075 1125);
FORCEADD OFFPAGE..2
(3875 1175);
FORCEPROP 2 LAST $XR1 113 
J 0
(4184 1175);
DISPLAY 0.638298 (4184 1175);
PAINT MONO (4184 1175);
FORCEPROP 2 LAST $XR0 112 
J 0
(4064 1175);
DISPLAY 0.638298 (4064 1175);
PAINT MONO (4064 1175);
FORCEPROP 2 LAST CDS_LIB standard
J 0
(3875 1175);
PAINT MONO (3875 1175);
DISPLAY INVISIBLE (3875 1175);
FORCEPROP 1 LAST OFFPAGE TRUE
J 0
(4200 1050);
DISPLAY 1.170213 (4200 1050);
PAINT GREEN (4200 1050);
DISPLAY INVISIBLE (4200 1050);
FORCEPROP 1 LAST COMMENT_BODY TRUE
J 0
(3830 1080);
DISPLAY 1.170213 (3830 1080);
PAINT GREEN (3830 1080);
DISPLAY INVISIBLE (3830 1080);
FORCEPROP 2 LAST PATH I119
J 0
(4050 1250);
DISPLAY 1.021277 (4050 1250);
DISPLAY INVISIBLE (4050 1250);
FORCEADD TAP..1
R 2
(-650 25);
FORCEPROP 3 LASTPIN (-600 25) SIG_NAME M_H_CPU1_SB_CB<3>
J 0
(-590 35);
DISPLAY 0.659574 (-590 35);
PAINT MONO (-590 35);
DISPLAY INVISIBLE (-590 35);
FORCEPROP 1 LASTPIN (-600 25) BN 3
J 2
(-588 33);
DISPLAY 0.680851 (-588 33);
PAINT GREEN (-588 33);
FORCEPROP 2 LAST CDS_LIB standard
J 0
(-650 25);
DISPLAY INVISIBLE (-650 25);
FORCEPROP 1 LAST BODY_TYPE PLUMBING
J 2
(-650 75);
DISPLAY 0.872340 (-650 75);
PAINT GREEN (-650 75);
DISPLAY INVISIBLE (-650 75);
FORCEPROP 1 LAST HDL_TAP TRUE
J 2
(-975 -100);
DISPLAY 0.872340 (-975 -100);
DISPLAY INVISIBLE (-975 -100);
FORCEPROP 1 LAST PATH I12
J 2
(-648 25);
DISPLAY 0.872340 (-648 25);
PAINT GREEN (-648 25);
DISPLAY INVISIBLE (-648 25);
FORCEADD TAP..1
(2775 1425);
FORCEPROP 3 LASTPIN (2725 1425) SIG_NAME M_H_CPU1_SA_CA<4>
J 0
(2735 1435);
DISPLAY 0.659574 (2735 1435);
PAINT MONO (2735 1435);
DISPLAY INVISIBLE (2735 1435);
FORCEPROP 1 LASTPIN (2725 1425) BN 4
J 0
(2713 1433);
DISPLAY 0.680851 (2713 1433);
PAINT GREEN (2713 1433);
FORCEPROP 2 LAST CDS_LIB standard
J 0
(2775 1425);
DISPLAY INVISIBLE (2775 1425);
FORCEPROP 1 LAST BODY_TYPE PLUMBING
J 0
(2775 1475);
DISPLAY 0.872340 (2775 1475);
PAINT GREEN (2775 1475);
DISPLAY INVISIBLE (2775 1475);
FORCEPROP 1 LAST HDL_TAP TRUE
J 0
(3100 1300);
DISPLAY 0.872340 (3100 1300);
DISPLAY INVISIBLE (3100 1300);
FORCEPROP 1 LAST PATH I120
J 0
(2773 1425);
DISPLAY 0.872340 (2773 1425);
PAINT GREEN (2773 1425);
DISPLAY INVISIBLE (2773 1425);
FORCEADD TAP..1
(2775 1525);
FORCEPROP 3 LASTPIN (2725 1525) SIG_NAME M_H_CPU1_SA_CA<6>
J 0
(2735 1535);
DISPLAY 0.659574 (2735 1535);
PAINT MONO (2735 1535);
DISPLAY INVISIBLE (2735 1535);
FORCEPROP 1 LASTPIN (2725 1525) BN 6
J 0
(2713 1533);
DISPLAY 0.680851 (2713 1533);
PAINT GREEN (2713 1533);
FORCEPROP 2 LAST CDS_LIB standard
J 0
(2775 1525);
DISPLAY INVISIBLE (2775 1525);
FORCEPROP 1 LAST BODY_TYPE PLUMBING
J 0
(2775 1575);
DISPLAY 0.872340 (2775 1575);
PAINT GREEN (2775 1575);
DISPLAY INVISIBLE (2775 1575);
FORCEPROP 1 LAST HDL_TAP TRUE
J 0
(3100 1400);
DISPLAY 0.872340 (3100 1400);
DISPLAY INVISIBLE (3100 1400);
FORCEPROP 1 LAST PATH I121
J 0
(2773 1525);
DISPLAY 0.872340 (2773 1525);
PAINT GREEN (2773 1525);
DISPLAY INVISIBLE (2773 1525);
FORCEADD TAP..1
(2775 1475);
FORCEPROP 3 LASTPIN (2725 1475) SIG_NAME M_H_CPU1_SA_CA<5>
J 0
(2735 1485);
DISPLAY 0.659574 (2735 1485);
PAINT MONO (2735 1485);
DISPLAY INVISIBLE (2735 1485);
FORCEPROP 1 LASTPIN (2725 1475) BN 5
J 0
(2713 1483);
DISPLAY 0.680851 (2713 1483);
PAINT GREEN (2713 1483);
FORCEPROP 2 LAST CDS_LIB standard
J 0
(2775 1475);
DISPLAY INVISIBLE (2775 1475);
FORCEPROP 1 LAST BODY_TYPE PLUMBING
J 0
(2775 1525);
DISPLAY 0.872340 (2775 1525);
PAINT GREEN (2775 1525);
DISPLAY INVISIBLE (2775 1525);
FORCEPROP 1 LAST HDL_TAP TRUE
J 0
(3100 1350);
DISPLAY 0.872340 (3100 1350);
DISPLAY INVISIBLE (3100 1350);
FORCEPROP 1 LAST PATH I122
J 0
(2773 1475);
DISPLAY 0.872340 (2773 1475);
PAINT GREEN (2773 1475);
DISPLAY INVISIBLE (2773 1475);
FORCEADD TAP..1
(2775 1375);
FORCEPROP 3 LASTPIN (2725 1375) SIG_NAME M_H_CPU1_SA_CA<3>
J 0
(2735 1385);
DISPLAY 0.659574 (2735 1385);
PAINT MONO (2735 1385);
DISPLAY INVISIBLE (2735 1385);
FORCEPROP 1 LASTPIN (2725 1375) BN 3
J 0
(2713 1383);
DISPLAY 0.680851 (2713 1383);
PAINT GREEN (2713 1383);
FORCEPROP 2 LAST CDS_LIB standard
J 0
(2775 1375);
DISPLAY INVISIBLE (2775 1375);
FORCEPROP 1 LAST BODY_TYPE PLUMBING
J 0
(2775 1425);
DISPLAY 0.872340 (2775 1425);
PAINT GREEN (2775 1425);
DISPLAY INVISIBLE (2775 1425);
FORCEPROP 1 LAST HDL_TAP TRUE
J 0
(3100 1250);
DISPLAY 0.872340 (3100 1250);
DISPLAY INVISIBLE (3100 1250);
FORCEPROP 1 LAST PATH I123
J 0
(2773 1375);
DISPLAY 0.872340 (2773 1375);
PAINT GREEN (2773 1375);
DISPLAY INVISIBLE (2773 1375);
FORCEADD TAP..1
(2775 1775);
FORCEPROP 3 LASTPIN (2725 1775) SIG_NAME M_H_CPU1_SB_DQS_DN<2>
J 0
(2735 1785);
DISPLAY 0.659574 (2735 1785);
PAINT MONO (2735 1785);
DISPLAY INVISIBLE (2735 1785);
FORCEPROP 1 LASTPIN (2725 1775) BN 2
J 0
(2713 1783);
DISPLAY 0.680851 (2713 1783);
PAINT GREEN (2713 1783);
FORCEPROP 2 LAST CDS_LIB standard
J 0
(2775 1775);
DISPLAY INVISIBLE (2775 1775);
FORCEPROP 1 LAST BODY_TYPE PLUMBING
J 0
(2775 1825);
DISPLAY 0.872340 (2775 1825);
PAINT GREEN (2775 1825);
DISPLAY INVISIBLE (2775 1825);
FORCEPROP 1 LAST HDL_TAP TRUE
J 0
(3100 1650);
DISPLAY 0.872340 (3100 1650);
DISPLAY INVISIBLE (3100 1650);
FORCEPROP 1 LAST PATH I124
J 0
(2773 1775);
DISPLAY 0.872340 (2773 1775);
PAINT GREEN (2773 1775);
DISPLAY INVISIBLE (2773 1775);
FORCEADD TAP..1
(2775 1825);
FORCEPROP 3 LASTPIN (2725 1825) SIG_NAME M_H_CPU1_SB_DQS_DN<3>
J 0
(2735 1835);
DISPLAY 0.659574 (2735 1835);
PAINT MONO (2735 1835);
DISPLAY INVISIBLE (2735 1835);
FORCEPROP 1 LASTPIN (2725 1825) BN 3
J 0
(2713 1833);
DISPLAY 0.680851 (2713 1833);
PAINT GREEN (2713 1833);
FORCEPROP 2 LAST CDS_LIB standard
J 0
(2775 1825);
DISPLAY INVISIBLE (2775 1825);
FORCEPROP 1 LAST BODY_TYPE PLUMBING
J 0
(2775 1875);
DISPLAY 0.872340 (2775 1875);
PAINT GREEN (2775 1875);
DISPLAY INVISIBLE (2775 1875);
FORCEPROP 1 LAST HDL_TAP TRUE
J 0
(3100 1700);
DISPLAY 0.872340 (3100 1700);
DISPLAY INVISIBLE (3100 1700);
FORCEPROP 1 LAST PATH I125
J 0
(2773 1825);
DISPLAY 0.872340 (2773 1825);
PAINT GREEN (2773 1825);
DISPLAY INVISIBLE (2773 1825);
FORCEADD TAP..1
(2775 1875);
FORCEPROP 3 LASTPIN (2725 1875) SIG_NAME M_H_CPU1_SB_DQS_DN<4>
J 0
(2735 1885);
DISPLAY 0.659574 (2735 1885);
PAINT MONO (2735 1885);
DISPLAY INVISIBLE (2735 1885);
FORCEPROP 1 LASTPIN (2725 1875) BN 4
J 0
(2713 1883);
DISPLAY 0.680851 (2713 1883);
PAINT GREEN (2713 1883);
FORCEPROP 2 LAST CDS_LIB standard
J 0
(2775 1875);
DISPLAY INVISIBLE (2775 1875);
FORCEPROP 1 LAST BODY_TYPE PLUMBING
J 0
(2775 1925);
DISPLAY 0.872340 (2775 1925);
PAINT GREEN (2775 1925);
DISPLAY INVISIBLE (2775 1925);
FORCEPROP 1 LAST HDL_TAP TRUE
J 0
(3100 1750);
DISPLAY 0.872340 (3100 1750);
DISPLAY INVISIBLE (3100 1750);
FORCEPROP 1 LAST PATH I126
J 0
(2773 1875);
DISPLAY 0.872340 (2773 1875);
PAINT GREEN (2773 1875);
DISPLAY INVISIBLE (2773 1875);
FORCEADD TAP..1
(2775 1725);
FORCEPROP 3 LASTPIN (2725 1725) SIG_NAME M_H_CPU1_SB_DQS_DN<1>
J 0
(2735 1735);
DISPLAY 0.659574 (2735 1735);
PAINT MONO (2735 1735);
DISPLAY INVISIBLE (2735 1735);
FORCEPROP 1 LASTPIN (2725 1725) BN 1
J 0
(2713 1733);
DISPLAY 0.680851 (2713 1733);
PAINT GREEN (2713 1733);
FORCEPROP 2 LAST CDS_LIB standard
J 0
(2775 1725);
DISPLAY INVISIBLE (2775 1725);
FORCEPROP 1 LAST BODY_TYPE PLUMBING
J 0
(2775 1775);
DISPLAY 0.872340 (2775 1775);
PAINT GREEN (2775 1775);
DISPLAY INVISIBLE (2775 1775);
FORCEPROP 1 LAST HDL_TAP TRUE
J 0
(3100 1600);
DISPLAY 0.872340 (3100 1600);
DISPLAY INVISIBLE (3100 1600);
FORCEPROP 1 LAST PATH I127
J 0
(2773 1725);
DISPLAY 0.872340 (2773 1725);
PAINT GREEN (2773 1725);
DISPLAY INVISIBLE (2773 1725);
FORCEADD TAP..1
(2775 1675);
FORCEPROP 3 LASTPIN (2725 1675) SIG_NAME M_H_CPU1_SB_DQS_DN<0>
J 0
(2735 1685);
DISPLAY 0.659574 (2735 1685);
PAINT MONO (2735 1685);
DISPLAY INVISIBLE (2735 1685);
FORCEPROP 1 LASTPIN (2725 1675) BN 0
J 0
(2713 1683);
DISPLAY 0.680851 (2713 1683);
PAINT GREEN (2713 1683);
FORCEPROP 2 LAST CDS_LIB standard
J 0
(2775 1675);
DISPLAY INVISIBLE (2775 1675);
FORCEPROP 1 LAST BODY_TYPE PLUMBING
J 0
(2775 1725);
DISPLAY 0.872340 (2775 1725);
PAINT GREEN (2775 1725);
DISPLAY INVISIBLE (2775 1725);
FORCEPROP 1 LAST HDL_TAP TRUE
J 0
(3100 1550);
DISPLAY 0.872340 (3100 1550);
DISPLAY INVISIBLE (3100 1550);
FORCEPROP 1 LAST PATH I128
J 0
(2773 1675);
DISPLAY 0.872340 (2773 1675);
PAINT GREEN (2773 1675);
DISPLAY INVISIBLE (2773 1675);
FORCEADD TAP..1
(2775 2125);
FORCEPROP 3 LASTPIN (2725 2125) SIG_NAME M_H_CPU1_SB_DQS_DN<9>
J 0
(2735 2135);
DISPLAY 0.659574 (2735 2135);
PAINT MONO (2735 2135);
DISPLAY INVISIBLE (2735 2135);
FORCEPROP 1 LASTPIN (2725 2125) BN 9
J 0
(2713 2133);
DISPLAY 0.680851 (2713 2133);
PAINT GREEN (2713 2133);
FORCEPROP 2 LAST CDS_LIB standard
J 0
(2775 2125);
DISPLAY INVISIBLE (2775 2125);
FORCEPROP 1 LAST BODY_TYPE PLUMBING
J 0
(2775 2175);
DISPLAY 0.872340 (2775 2175);
PAINT GREEN (2775 2175);
DISPLAY INVISIBLE (2775 2175);
FORCEPROP 1 LAST HDL_TAP TRUE
J 0
(3100 2000);
DISPLAY 0.872340 (3100 2000);
DISPLAY INVISIBLE (3100 2000);
FORCEPROP 1 LAST PATH I129
J 0
(2773 2125);
DISPLAY 0.872340 (2773 2125);
PAINT GREEN (2773 2125);
DISPLAY INVISIBLE (2773 2125);
FORCEADD TAP..1
R 2
(-650 -25);
FORCEPROP 3 LASTPIN (-600 -25) SIG_NAME M_H_CPU1_SB_CB<2>
J 0
(-590 -15);
DISPLAY 0.659574 (-590 -15);
PAINT MONO (-590 -15);
DISPLAY INVISIBLE (-590 -15);
FORCEPROP 1 LASTPIN (-600 -25) BN 2
J 2
(-588 -17);
DISPLAY 0.680851 (-588 -17);
PAINT GREEN (-588 -17);
FORCEPROP 2 LAST CDS_LIB standard
J 0
(-650 -25);
DISPLAY INVISIBLE (-650 -25);
FORCEPROP 1 LAST BODY_TYPE PLUMBING
J 2
(-650 25);
DISPLAY 0.872340 (-650 25);
PAINT GREEN (-650 25);
DISPLAY INVISIBLE (-650 25);
FORCEPROP 1 LAST HDL_TAP TRUE
J 2
(-975 -150);
DISPLAY 0.872340 (-975 -150);
DISPLAY INVISIBLE (-975 -150);
FORCEPROP 1 LAST PATH I13
J 2
(-648 -25);
DISPLAY 0.872340 (-648 -25);
PAINT GREEN (-648 -25);
DISPLAY INVISIBLE (-648 -25);
FORCEADD TAP..1
(2775 2075);
FORCEPROP 3 LASTPIN (2725 2075) SIG_NAME M_H_CPU1_SB_DQS_DN<8>
J 0
(2735 2085);
DISPLAY 0.659574 (2735 2085);
PAINT MONO (2735 2085);
DISPLAY INVISIBLE (2735 2085);
FORCEPROP 1 LASTPIN (2725 2075) BN 8
J 0
(2713 2083);
DISPLAY 0.680851 (2713 2083);
PAINT GREEN (2713 2083);
FORCEPROP 2 LAST CDS_LIB standard
J 0
(2775 2075);
DISPLAY INVISIBLE (2775 2075);
FORCEPROP 1 LAST BODY_TYPE PLUMBING
J 0
(2775 2125);
DISPLAY 0.872340 (2775 2125);
PAINT GREEN (2775 2125);
DISPLAY INVISIBLE (2775 2125);
FORCEPROP 1 LAST HDL_TAP TRUE
J 0
(3100 1950);
DISPLAY 0.872340 (3100 1950);
DISPLAY INVISIBLE (3100 1950);
FORCEPROP 1 LAST PATH I130
J 0
(2773 2075);
DISPLAY 0.872340 (2773 2075);
PAINT GREEN (2773 2075);
DISPLAY INVISIBLE (2773 2075);
FORCEADD TAP..1
(2775 2025);
FORCEPROP 3 LASTPIN (2725 2025) SIG_NAME M_H_CPU1_SB_DQS_DN<7>
J 0
(2735 2035);
DISPLAY 0.659574 (2735 2035);
PAINT MONO (2735 2035);
DISPLAY INVISIBLE (2735 2035);
FORCEPROP 1 LASTPIN (2725 2025) BN 7
J 0
(2713 2033);
DISPLAY 0.680851 (2713 2033);
PAINT GREEN (2713 2033);
FORCEPROP 2 LAST CDS_LIB standard
J 0
(2775 2025);
DISPLAY INVISIBLE (2775 2025);
FORCEPROP 1 LAST BODY_TYPE PLUMBING
J 0
(2775 2075);
DISPLAY 0.872340 (2775 2075);
PAINT GREEN (2775 2075);
DISPLAY INVISIBLE (2775 2075);
FORCEPROP 1 LAST HDL_TAP TRUE
J 0
(3100 1900);
DISPLAY 0.872340 (3100 1900);
DISPLAY INVISIBLE (3100 1900);
FORCEPROP 1 LAST PATH I131
J 0
(2773 2025);
DISPLAY 0.872340 (2773 2025);
PAINT GREEN (2773 2025);
DISPLAY INVISIBLE (2773 2025);
FORCEADD TAP..1
(2775 1925);
FORCEPROP 3 LASTPIN (2725 1925) SIG_NAME M_H_CPU1_SB_DQS_DN<5>
J 0
(2735 1935);
DISPLAY 0.659574 (2735 1935);
PAINT MONO (2735 1935);
DISPLAY INVISIBLE (2735 1935);
FORCEPROP 1 LASTPIN (2725 1925) BN 5
J 0
(2713 1933);
DISPLAY 0.680851 (2713 1933);
PAINT GREEN (2713 1933);
FORCEPROP 2 LAST CDS_LIB standard
J 0
(2775 1925);
DISPLAY INVISIBLE (2775 1925);
FORCEPROP 1 LAST BODY_TYPE PLUMBING
J 0
(2775 1975);
DISPLAY 0.872340 (2775 1975);
PAINT GREEN (2775 1975);
DISPLAY INVISIBLE (2775 1975);
FORCEPROP 1 LAST HDL_TAP TRUE
J 0
(3100 1800);
DISPLAY 0.872340 (3100 1800);
DISPLAY INVISIBLE (3100 1800);
FORCEPROP 1 LAST PATH I132
J 0
(2773 1925);
DISPLAY 0.872340 (2773 1925);
PAINT GREEN (2773 1925);
DISPLAY INVISIBLE (2773 1925);
FORCEADD TAP..1
(2775 1975);
FORCEPROP 3 LASTPIN (2725 1975) SIG_NAME M_H_CPU1_SB_DQS_DN<6>
J 0
(2735 1985);
DISPLAY 0.659574 (2735 1985);
PAINT MONO (2735 1985);
DISPLAY INVISIBLE (2735 1985);
FORCEPROP 1 LASTPIN (2725 1975) BN 6
J 0
(2713 1983);
DISPLAY 0.680851 (2713 1983);
PAINT GREEN (2713 1983);
FORCEPROP 2 LAST CDS_LIB standard
J 0
(2775 1975);
DISPLAY INVISIBLE (2775 1975);
FORCEPROP 1 LAST BODY_TYPE PLUMBING
J 0
(2775 2025);
DISPLAY 0.872340 (2775 2025);
PAINT GREEN (2775 2025);
DISPLAY INVISIBLE (2775 2025);
FORCEPROP 1 LAST HDL_TAP TRUE
J 0
(3100 1850);
DISPLAY 0.872340 (3100 1850);
DISPLAY INVISIBLE (3100 1850);
FORCEPROP 1 LAST PATH I133
J 0
(2773 1975);
DISPLAY 0.872340 (2773 1975);
PAINT GREEN (2773 1975);
DISPLAY INVISIBLE (2773 1975);
FORCEADD TAP..1
(2775 2275);
FORCEPROP 3 LASTPIN (2725 2275) SIG_NAME M_H_CPU1_SB_DQS_DP<1>
J 0
(2735 2285);
DISPLAY 0.659574 (2735 2285);
PAINT MONO (2735 2285);
DISPLAY INVISIBLE (2735 2285);
FORCEPROP 1 LASTPIN (2725 2275) BN 1
J 0
(2713 2283);
DISPLAY 0.680851 (2713 2283);
PAINT GREEN (2713 2283);
FORCEPROP 2 LAST CDS_LIB standard
J 0
(2775 2275);
DISPLAY INVISIBLE (2775 2275);
FORCEPROP 1 LAST BODY_TYPE PLUMBING
J 0
(2775 2325);
DISPLAY 0.872340 (2775 2325);
PAINT GREEN (2775 2325);
DISPLAY INVISIBLE (2775 2325);
FORCEPROP 1 LAST HDL_TAP TRUE
J 0
(3100 2150);
DISPLAY 0.872340 (3100 2150);
DISPLAY INVISIBLE (3100 2150);
FORCEPROP 1 LAST PATH I134
J 0
(2773 2275);
DISPLAY 0.872340 (2773 2275);
PAINT GREEN (2773 2275);
DISPLAY INVISIBLE (2773 2275);
FORCEADD TAP..1
(2775 2325);
FORCEPROP 3 LASTPIN (2725 2325) SIG_NAME M_H_CPU1_SB_DQS_DP<2>
J 0
(2735 2335);
DISPLAY 0.659574 (2735 2335);
PAINT MONO (2735 2335);
DISPLAY INVISIBLE (2735 2335);
FORCEPROP 1 LASTPIN (2725 2325) BN 2
J 0
(2713 2333);
DISPLAY 0.680851 (2713 2333);
PAINT GREEN (2713 2333);
FORCEPROP 2 LAST CDS_LIB standard
J 0
(2775 2325);
DISPLAY INVISIBLE (2775 2325);
FORCEPROP 1 LAST BODY_TYPE PLUMBING
J 0
(2775 2375);
DISPLAY 0.872340 (2775 2375);
PAINT GREEN (2775 2375);
DISPLAY INVISIBLE (2775 2375);
FORCEPROP 1 LAST HDL_TAP TRUE
J 0
(3100 2200);
DISPLAY 0.872340 (3100 2200);
DISPLAY INVISIBLE (3100 2200);
FORCEPROP 1 LAST PATH I135
J 0
(2773 2325);
DISPLAY 0.872340 (2773 2325);
PAINT GREEN (2773 2325);
DISPLAY INVISIBLE (2773 2325);
FORCEADD TAP..1
(2775 2375);
FORCEPROP 3 LASTPIN (2725 2375) SIG_NAME M_H_CPU1_SB_DQS_DP<3>
J 0
(2735 2385);
DISPLAY 0.659574 (2735 2385);
PAINT MONO (2735 2385);
DISPLAY INVISIBLE (2735 2385);
FORCEPROP 1 LASTPIN (2725 2375) BN 3
J 0
(2713 2383);
DISPLAY 0.680851 (2713 2383);
PAINT GREEN (2713 2383);
FORCEPROP 2 LAST CDS_LIB standard
J 0
(2775 2375);
DISPLAY INVISIBLE (2775 2375);
FORCEPROP 1 LAST BODY_TYPE PLUMBING
J 0
(2775 2425);
DISPLAY 0.872340 (2775 2425);
PAINT GREEN (2775 2425);
DISPLAY INVISIBLE (2775 2425);
FORCEPROP 1 LAST HDL_TAP TRUE
J 0
(3100 2250);
DISPLAY 0.872340 (3100 2250);
DISPLAY INVISIBLE (3100 2250);
FORCEPROP 1 LAST PATH I136
J 0
(2773 2375);
DISPLAY 0.872340 (2773 2375);
PAINT GREEN (2773 2375);
DISPLAY INVISIBLE (2773 2375);
FORCEADD TAP..1
(2775 2225);
FORCEPROP 3 LASTPIN (2725 2225) SIG_NAME M_H_CPU1_SB_DQS_DP<0>
J 0
(2735 2235);
DISPLAY 0.659574 (2735 2235);
PAINT MONO (2735 2235);
DISPLAY INVISIBLE (2735 2235);
FORCEPROP 1 LASTPIN (2725 2225) BN 0
J 0
(2713 2233);
DISPLAY 0.680851 (2713 2233);
PAINT GREEN (2713 2233);
FORCEPROP 2 LAST CDS_LIB standard
J 0
(2775 2225);
DISPLAY INVISIBLE (2775 2225);
FORCEPROP 1 LAST BODY_TYPE PLUMBING
J 0
(2775 2275);
DISPLAY 0.872340 (2775 2275);
PAINT GREEN (2775 2275);
DISPLAY INVISIBLE (2775 2275);
FORCEPROP 1 LAST HDL_TAP TRUE
J 0
(3100 2100);
DISPLAY 0.872340 (3100 2100);
DISPLAY INVISIBLE (3100 2100);
FORCEPROP 1 LAST PATH I137
J 0
(2773 2225);
DISPLAY 0.872340 (2773 2225);
PAINT GREEN (2773 2225);
DISPLAY INVISIBLE (2773 2225);
FORCEADD TAP..1
(2775 2625);
FORCEPROP 3 LASTPIN (2725 2625) SIG_NAME M_H_CPU1_SB_DQS_DP<8>
J 0
(2735 2635);
DISPLAY 0.659574 (2735 2635);
PAINT MONO (2735 2635);
DISPLAY INVISIBLE (2735 2635);
FORCEPROP 1 LASTPIN (2725 2625) BN 8
J 0
(2713 2633);
DISPLAY 0.680851 (2713 2633);
PAINT GREEN (2713 2633);
FORCEPROP 2 LAST CDS_LIB standard
J 0
(2775 2625);
DISPLAY INVISIBLE (2775 2625);
FORCEPROP 1 LAST BODY_TYPE PLUMBING
J 0
(2775 2675);
DISPLAY 0.872340 (2775 2675);
PAINT GREEN (2775 2675);
DISPLAY INVISIBLE (2775 2675);
FORCEPROP 1 LAST HDL_TAP TRUE
J 0
(3100 2500);
DISPLAY 0.872340 (3100 2500);
DISPLAY INVISIBLE (3100 2500);
FORCEPROP 1 LAST PATH I138
J 0
(2773 2625);
DISPLAY 0.872340 (2773 2625);
PAINT GREEN (2773 2625);
DISPLAY INVISIBLE (2773 2625);
FORCEADD TAP..1
(2775 2575);
FORCEPROP 3 LASTPIN (2725 2575) SIG_NAME M_H_CPU1_SB_DQS_DP<7>
J 0
(2735 2585);
DISPLAY 0.659574 (2735 2585);
PAINT MONO (2735 2585);
DISPLAY INVISIBLE (2735 2585);
FORCEPROP 1 LASTPIN (2725 2575) BN 7
J 0
(2713 2583);
DISPLAY 0.680851 (2713 2583);
PAINT GREEN (2713 2583);
FORCEPROP 2 LAST CDS_LIB standard
J 0
(2775 2575);
DISPLAY INVISIBLE (2775 2575);
FORCEPROP 1 LAST BODY_TYPE PLUMBING
J 0
(2775 2625);
DISPLAY 0.872340 (2775 2625);
PAINT GREEN (2775 2625);
DISPLAY INVISIBLE (2775 2625);
FORCEPROP 1 LAST HDL_TAP TRUE
J 0
(3100 2450);
DISPLAY 0.872340 (3100 2450);
DISPLAY INVISIBLE (3100 2450);
FORCEPROP 1 LAST PATH I139
J 0
(2773 2575);
DISPLAY 0.872340 (2773 2575);
PAINT GREEN (2773 2575);
DISPLAY INVISIBLE (2773 2575);
FORCEADD TAP..1
R 2
(-650 75);
FORCEPROP 3 LASTPIN (-600 75) SIG_NAME M_H_CPU1_SB_CB<4>
J 0
(-590 85);
DISPLAY 0.659574 (-590 85);
PAINT MONO (-590 85);
DISPLAY INVISIBLE (-590 85);
FORCEPROP 1 LASTPIN (-600 75) BN 4
J 2
(-588 83);
DISPLAY 0.680851 (-588 83);
PAINT GREEN (-588 83);
FORCEPROP 2 LAST CDS_LIB standard
J 0
(-650 75);
DISPLAY INVISIBLE (-650 75);
FORCEPROP 1 LAST BODY_TYPE PLUMBING
J 2
(-650 125);
DISPLAY 0.872340 (-650 125);
PAINT GREEN (-650 125);
DISPLAY INVISIBLE (-650 125);
FORCEPROP 1 LAST HDL_TAP TRUE
J 2
(-975 -50);
DISPLAY 0.872340 (-975 -50);
DISPLAY INVISIBLE (-975 -50);
FORCEPROP 1 LAST PATH I14
J 2
(-648 75);
DISPLAY 0.872340 (-648 75);
PAINT GREEN (-648 75);
DISPLAY INVISIBLE (-648 75);
FORCEADD TAP..1
(2775 2475);
FORCEPROP 3 LASTPIN (2725 2475) SIG_NAME M_H_CPU1_SB_DQS_DP<5>
J 0
(2735 2485);
DISPLAY 0.659574 (2735 2485);
PAINT MONO (2735 2485);
DISPLAY INVISIBLE (2735 2485);
FORCEPROP 1 LASTPIN (2725 2475) BN 5
J 0
(2713 2483);
DISPLAY 0.680851 (2713 2483);
PAINT GREEN (2713 2483);
FORCEPROP 2 LAST CDS_LIB standard
J 0
(2775 2475);
DISPLAY INVISIBLE (2775 2475);
FORCEPROP 1 LAST BODY_TYPE PLUMBING
J 0
(2775 2525);
DISPLAY 0.872340 (2775 2525);
PAINT GREEN (2775 2525);
DISPLAY INVISIBLE (2775 2525);
FORCEPROP 1 LAST HDL_TAP TRUE
J 0
(3100 2350);
DISPLAY 0.872340 (3100 2350);
DISPLAY INVISIBLE (3100 2350);
FORCEPROP 1 LAST PATH I140
J 0
(2773 2475);
DISPLAY 0.872340 (2773 2475);
PAINT GREEN (2773 2475);
DISPLAY INVISIBLE (2773 2475);
FORCEADD TAP..1
(2775 2425);
FORCEPROP 3 LASTPIN (2725 2425) SIG_NAME M_H_CPU1_SB_DQS_DP<4>
J 0
(2735 2435);
DISPLAY 0.659574 (2735 2435);
PAINT MONO (2735 2435);
DISPLAY INVISIBLE (2735 2435);
FORCEPROP 1 LASTPIN (2725 2425) BN 4
J 0
(2713 2433);
DISPLAY 0.680851 (2713 2433);
PAINT GREEN (2713 2433);
FORCEPROP 2 LAST CDS_LIB standard
J 0
(2775 2425);
DISPLAY INVISIBLE (2775 2425);
FORCEPROP 1 LAST BODY_TYPE PLUMBING
J 0
(2775 2475);
DISPLAY 0.872340 (2775 2475);
PAINT GREEN (2775 2475);
DISPLAY INVISIBLE (2775 2475);
FORCEPROP 1 LAST HDL_TAP TRUE
J 0
(3100 2300);
DISPLAY 0.872340 (3100 2300);
DISPLAY INVISIBLE (3100 2300);
FORCEPROP 1 LAST PATH I141
J 0
(2773 2425);
DISPLAY 0.872340 (2773 2425);
PAINT GREEN (2773 2425);
DISPLAY INVISIBLE (2773 2425);
FORCEADD TAP..1
(2775 2525);
FORCEPROP 3 LASTPIN (2725 2525) SIG_NAME M_H_CPU1_SB_DQS_DP<6>
J 0
(2735 2535);
DISPLAY 0.659574 (2735 2535);
PAINT MONO (2735 2535);
DISPLAY INVISIBLE (2735 2535);
FORCEPROP 1 LASTPIN (2725 2525) BN 6
J 0
(2713 2533);
DISPLAY 0.680851 (2713 2533);
PAINT GREEN (2713 2533);
FORCEPROP 2 LAST CDS_LIB standard
J 0
(2775 2525);
DISPLAY INVISIBLE (2775 2525);
FORCEPROP 1 LAST BODY_TYPE PLUMBING
J 0
(2775 2575);
DISPLAY 0.872340 (2775 2575);
PAINT GREEN (2775 2575);
DISPLAY INVISIBLE (2775 2575);
FORCEPROP 1 LAST HDL_TAP TRUE
J 0
(3100 2400);
DISPLAY 0.872340 (3100 2400);
DISPLAY INVISIBLE (3100 2400);
FORCEPROP 1 LAST PATH I142
J 0
(2773 2525);
DISPLAY 0.872340 (2773 2525);
PAINT GREEN (2773 2525);
DISPLAY INVISIBLE (2773 2525);
FORCEADD TAP..1
(2775 2675);
FORCEPROP 3 LASTPIN (2725 2675) SIG_NAME M_H_CPU1_SB_DQS_DP<9>
J 0
(2735 2685);
DISPLAY 0.659574 (2735 2685);
PAINT MONO (2735 2685);
DISPLAY INVISIBLE (2735 2685);
FORCEPROP 1 LASTPIN (2725 2675) BN 9
J 0
(2713 2683);
DISPLAY 0.680851 (2713 2683);
PAINT GREEN (2713 2683);
FORCEPROP 2 LAST CDS_LIB standard
J 0
(2775 2675);
DISPLAY INVISIBLE (2775 2675);
FORCEPROP 1 LAST BODY_TYPE PLUMBING
J 0
(2775 2725);
DISPLAY 0.872340 (2775 2725);
PAINT GREEN (2775 2725);
DISPLAY INVISIBLE (2775 2725);
FORCEPROP 1 LAST HDL_TAP TRUE
J 0
(3100 2550);
DISPLAY 0.872340 (3100 2550);
DISPLAY INVISIBLE (3100 2550);
FORCEPROP 1 LAST PATH I143
J 0
(2773 2675);
DISPLAY 0.872340 (2773 2675);
PAINT GREEN (2773 2675);
DISPLAY INVISIBLE (2773 2675);
FORCEADD TAP..1
(2775 2875);
FORCEPROP 3 LASTPIN (2725 2875) SIG_NAME M_H_CPU1_SA_DQS_DN<1>
J 0
(2735 2885);
DISPLAY 0.659574 (2735 2885);
PAINT MONO (2735 2885);
DISPLAY INVISIBLE (2735 2885);
FORCEPROP 1 LASTPIN (2725 2875) BN 1
J 0
(2713 2883);
DISPLAY 0.680851 (2713 2883);
PAINT GREEN (2713 2883);
FORCEPROP 2 LAST CDS_LIB standard
J 0
(2775 2875);
DISPLAY INVISIBLE (2775 2875);
FORCEPROP 1 LAST BODY_TYPE PLUMBING
J 0
(2775 2925);
DISPLAY 0.872340 (2775 2925);
PAINT GREEN (2775 2925);
DISPLAY INVISIBLE (2775 2925);
FORCEPROP 1 LAST HDL_TAP TRUE
J 0
(3100 2750);
DISPLAY 0.872340 (3100 2750);
DISPLAY INVISIBLE (3100 2750);
FORCEPROP 1 LAST PATH I144
J 0
(2773 2875);
DISPLAY 0.872340 (2773 2875);
PAINT GREEN (2773 2875);
DISPLAY INVISIBLE (2773 2875);
FORCEADD TAP..1
(2775 2825);
FORCEPROP 3 LASTPIN (2725 2825) SIG_NAME M_H_CPU1_SA_DQS_DN<0>
J 0
(2735 2835);
DISPLAY 0.659574 (2735 2835);
PAINT MONO (2735 2835);
DISPLAY INVISIBLE (2735 2835);
FORCEPROP 1 LASTPIN (2725 2825) BN 0
J 0
(2713 2833);
DISPLAY 0.680851 (2713 2833);
PAINT GREEN (2713 2833);
FORCEPROP 2 LAST CDS_LIB standard
J 0
(2775 2825);
DISPLAY INVISIBLE (2775 2825);
FORCEPROP 1 LAST BODY_TYPE PLUMBING
J 0
(2775 2875);
DISPLAY 0.872340 (2775 2875);
PAINT GREEN (2775 2875);
DISPLAY INVISIBLE (2775 2875);
FORCEPROP 1 LAST HDL_TAP TRUE
J 0
(3100 2700);
DISPLAY 0.872340 (3100 2700);
DISPLAY INVISIBLE (3100 2700);
FORCEPROP 1 LAST PATH I145
J 0
(2773 2825);
DISPLAY 0.872340 (2773 2825);
PAINT GREEN (2773 2825);
DISPLAY INVISIBLE (2773 2825);
FORCEADD TAP..1
(2775 3075);
FORCEPROP 3 LASTPIN (2725 3075) SIG_NAME M_H_CPU1_SA_DQS_DN<5>
J 0
(2735 3085);
DISPLAY 0.659574 (2735 3085);
PAINT MONO (2735 3085);
DISPLAY INVISIBLE (2735 3085);
FORCEPROP 1 LASTPIN (2725 3075) BN 5
J 0
(2713 3083);
DISPLAY 0.680851 (2713 3083);
PAINT GREEN (2713 3083);
FORCEPROP 2 LAST CDS_LIB standard
J 0
(2775 3075);
DISPLAY INVISIBLE (2775 3075);
FORCEPROP 1 LAST BODY_TYPE PLUMBING
J 0
(2775 3125);
DISPLAY 0.872340 (2775 3125);
PAINT GREEN (2775 3125);
DISPLAY INVISIBLE (2775 3125);
FORCEPROP 1 LAST HDL_TAP TRUE
J 0
(3100 2950);
DISPLAY 0.872340 (3100 2950);
DISPLAY INVISIBLE (3100 2950);
FORCEPROP 1 LAST PATH I146
J 0
(2773 3075);
DISPLAY 0.872340 (2773 3075);
PAINT GREEN (2773 3075);
DISPLAY INVISIBLE (2773 3075);
FORCEADD TAP..1
(2775 3125);
FORCEPROP 3 LASTPIN (2725 3125) SIG_NAME M_H_CPU1_SA_DQS_DN<6>
J 0
(2735 3135);
DISPLAY 0.659574 (2735 3135);
PAINT MONO (2735 3135);
DISPLAY INVISIBLE (2735 3135);
FORCEPROP 1 LASTPIN (2725 3125) BN 6
J 0
(2713 3133);
DISPLAY 0.680851 (2713 3133);
PAINT GREEN (2713 3133);
FORCEPROP 2 LAST CDS_LIB standard
J 0
(2775 3125);
DISPLAY INVISIBLE (2775 3125);
FORCEPROP 1 LAST BODY_TYPE PLUMBING
J 0
(2775 3175);
DISPLAY 0.872340 (2775 3175);
PAINT GREEN (2775 3175);
DISPLAY INVISIBLE (2775 3175);
FORCEPROP 1 LAST HDL_TAP TRUE
J 0
(3100 3000);
DISPLAY 0.872340 (3100 3000);
DISPLAY INVISIBLE (3100 3000);
FORCEPROP 1 LAST PATH I147
J 0
(2773 3125);
DISPLAY 0.872340 (2773 3125);
PAINT GREEN (2773 3125);
DISPLAY INVISIBLE (2773 3125);
FORCEADD TAP..1
(2775 2975);
FORCEPROP 3 LASTPIN (2725 2975) SIG_NAME M_H_CPU1_SA_DQS_DN<3>
J 0
(2735 2985);
DISPLAY 0.659574 (2735 2985);
PAINT MONO (2735 2985);
DISPLAY INVISIBLE (2735 2985);
FORCEPROP 1 LASTPIN (2725 2975) BN 3
J 0
(2713 2983);
DISPLAY 0.680851 (2713 2983);
PAINT GREEN (2713 2983);
FORCEPROP 2 LAST CDS_LIB standard
J 0
(2775 2975);
DISPLAY INVISIBLE (2775 2975);
FORCEPROP 1 LAST BODY_TYPE PLUMBING
J 0
(2775 3025);
DISPLAY 0.872340 (2775 3025);
PAINT GREEN (2775 3025);
DISPLAY INVISIBLE (2775 3025);
FORCEPROP 1 LAST HDL_TAP TRUE
J 0
(3100 2850);
DISPLAY 0.872340 (3100 2850);
DISPLAY INVISIBLE (3100 2850);
FORCEPROP 1 LAST PATH I148
J 0
(2773 2975);
DISPLAY 0.872340 (2773 2975);
PAINT GREEN (2773 2975);
DISPLAY INVISIBLE (2773 2975);
FORCEADD TAP..1
(2775 2925);
FORCEPROP 3 LASTPIN (2725 2925) SIG_NAME M_H_CPU1_SA_DQS_DN<2>
J 0
(2735 2935);
DISPLAY 0.659574 (2735 2935);
PAINT MONO (2735 2935);
DISPLAY INVISIBLE (2735 2935);
FORCEPROP 1 LASTPIN (2725 2925) BN 2
J 0
(2713 2933);
DISPLAY 0.680851 (2713 2933);
PAINT GREEN (2713 2933);
FORCEPROP 2 LAST CDS_LIB standard
J 0
(2775 2925);
DISPLAY INVISIBLE (2775 2925);
FORCEPROP 1 LAST BODY_TYPE PLUMBING
J 0
(2775 2975);
DISPLAY 0.872340 (2775 2975);
PAINT GREEN (2775 2975);
DISPLAY INVISIBLE (2775 2975);
FORCEPROP 1 LAST HDL_TAP TRUE
J 0
(3100 2800);
DISPLAY 0.872340 (3100 2800);
DISPLAY INVISIBLE (3100 2800);
FORCEPROP 1 LAST PATH I149
J 0
(2773 2925);
DISPLAY 0.872340 (2773 2925);
PAINT GREEN (2773 2925);
DISPLAY INVISIBLE (2773 2925);
FORCEADD TAP..1
R 2
(-650 175);
FORCEPROP 3 LASTPIN (-600 175) SIG_NAME M_H_CPU1_SB_CB<6>
J 0
(-590 185);
DISPLAY 0.659574 (-590 185);
PAINT MONO (-590 185);
DISPLAY INVISIBLE (-590 185);
FORCEPROP 1 LASTPIN (-600 175) BN 6
J 2
(-588 183);
DISPLAY 0.680851 (-588 183);
PAINT GREEN (-588 183);
FORCEPROP 2 LAST CDS_LIB standard
J 0
(-650 175);
DISPLAY INVISIBLE (-650 175);
FORCEPROP 1 LAST BODY_TYPE PLUMBING
J 2
(-650 225);
DISPLAY 0.872340 (-650 225);
PAINT GREEN (-650 225);
DISPLAY INVISIBLE (-650 225);
FORCEPROP 1 LAST HDL_TAP TRUE
J 2
(-975 50);
DISPLAY 0.872340 (-975 50);
DISPLAY INVISIBLE (-975 50);
FORCEPROP 1 LAST PATH I15
J 2
(-648 175);
DISPLAY 0.872340 (-648 175);
PAINT GREEN (-648 175);
DISPLAY INVISIBLE (-648 175);
FORCEADD TAP..1
(2775 3025);
FORCEPROP 3 LASTPIN (2725 3025) SIG_NAME M_H_CPU1_SA_DQS_DN<4>
J 0
(2735 3035);
DISPLAY 0.659574 (2735 3035);
PAINT MONO (2735 3035);
DISPLAY INVISIBLE (2735 3035);
FORCEPROP 1 LASTPIN (2725 3025) BN 4
J 0
(2713 3033);
DISPLAY 0.680851 (2713 3033);
PAINT GREEN (2713 3033);
FORCEPROP 2 LAST CDS_LIB standard
J 0
(2775 3025);
DISPLAY INVISIBLE (2775 3025);
FORCEPROP 1 LAST BODY_TYPE PLUMBING
J 0
(2775 3075);
DISPLAY 0.872340 (2775 3075);
PAINT GREEN (2775 3075);
DISPLAY INVISIBLE (2775 3075);
FORCEPROP 1 LAST HDL_TAP TRUE
J 0
(3100 2900);
DISPLAY 0.872340 (3100 2900);
DISPLAY INVISIBLE (3100 2900);
FORCEPROP 1 LAST PATH I150
J 0
(2773 3025);
DISPLAY 0.872340 (2773 3025);
PAINT GREEN (2773 3025);
DISPLAY INVISIBLE (2773 3025);
FORCEADD TAP..1
(2775 3275);
FORCEPROP 3 LASTPIN (2725 3275) SIG_NAME M_H_CPU1_SA_DQS_DN<9>
J 0
(2735 3285);
DISPLAY 0.659574 (2735 3285);
PAINT MONO (2735 3285);
DISPLAY INVISIBLE (2735 3285);
FORCEPROP 1 LASTPIN (2725 3275) BN 9
J 0
(2713 3283);
DISPLAY 0.680851 (2713 3283);
PAINT GREEN (2713 3283);
FORCEPROP 2 LAST CDS_LIB standard
J 0
(2775 3275);
DISPLAY INVISIBLE (2775 3275);
FORCEPROP 1 LAST BODY_TYPE PLUMBING
J 0
(2775 3325);
DISPLAY 0.872340 (2775 3325);
PAINT GREEN (2775 3325);
DISPLAY INVISIBLE (2775 3325);
FORCEPROP 1 LAST HDL_TAP TRUE
J 0
(3100 3150);
DISPLAY 0.872340 (3100 3150);
DISPLAY INVISIBLE (3100 3150);
FORCEPROP 1 LAST PATH I151
J 0
(2773 3275);
DISPLAY 0.872340 (2773 3275);
PAINT GREEN (2773 3275);
DISPLAY INVISIBLE (2773 3275);
FORCEADD TAP..1
(2775 3225);
FORCEPROP 3 LASTPIN (2725 3225) SIG_NAME M_H_CPU1_SA_DQS_DN<8>
J 0
(2735 3235);
DISPLAY 0.659574 (2735 3235);
PAINT MONO (2735 3235);
DISPLAY INVISIBLE (2735 3235);
FORCEPROP 1 LASTPIN (2725 3225) BN 8
J 0
(2713 3233);
DISPLAY 0.680851 (2713 3233);
PAINT GREEN (2713 3233);
FORCEPROP 2 LAST CDS_LIB standard
J 0
(2775 3225);
DISPLAY INVISIBLE (2775 3225);
FORCEPROP 1 LAST BODY_TYPE PLUMBING
J 0
(2775 3275);
DISPLAY 0.872340 (2775 3275);
PAINT GREEN (2775 3275);
DISPLAY INVISIBLE (2775 3275);
FORCEPROP 1 LAST HDL_TAP TRUE
J 0
(3100 3100);
DISPLAY 0.872340 (3100 3100);
DISPLAY INVISIBLE (3100 3100);
FORCEPROP 1 LAST PATH I152
J 0
(2773 3225);
DISPLAY 0.872340 (2773 3225);
PAINT GREEN (2773 3225);
DISPLAY INVISIBLE (2773 3225);
FORCEADD TAP..1
(2775 3375);
FORCEPROP 3 LASTPIN (2725 3375) SIG_NAME M_H_CPU1_SA_DQS_DP<0>
J 0
(2735 3385);
DISPLAY 0.659574 (2735 3385);
PAINT MONO (2735 3385);
DISPLAY INVISIBLE (2735 3385);
FORCEPROP 1 LASTPIN (2725 3375) BN 0
J 0
(2713 3383);
DISPLAY 0.680851 (2713 3383);
PAINT GREEN (2713 3383);
FORCEPROP 2 LAST CDS_LIB standard
J 0
(2775 3375);
DISPLAY INVISIBLE (2775 3375);
FORCEPROP 1 LAST BODY_TYPE PLUMBING
J 0
(2775 3425);
DISPLAY 0.872340 (2775 3425);
PAINT GREEN (2775 3425);
DISPLAY INVISIBLE (2775 3425);
FORCEPROP 1 LAST HDL_TAP TRUE
J 0
(3100 3250);
DISPLAY 0.872340 (3100 3250);
DISPLAY INVISIBLE (3100 3250);
FORCEPROP 1 LAST PATH I153
J 0
(2773 3375);
DISPLAY 0.872340 (2773 3375);
PAINT GREEN (2773 3375);
DISPLAY INVISIBLE (2773 3375);
FORCEADD TAP..1
(2775 3175);
FORCEPROP 3 LASTPIN (2725 3175) SIG_NAME M_H_CPU1_SA_DQS_DN<7>
J 0
(2735 3185);
DISPLAY 0.659574 (2735 3185);
PAINT MONO (2735 3185);
DISPLAY INVISIBLE (2735 3185);
FORCEPROP 1 LASTPIN (2725 3175) BN 7
J 0
(2713 3183);
DISPLAY 0.680851 (2713 3183);
PAINT GREEN (2713 3183);
FORCEPROP 2 LAST CDS_LIB standard
J 0
(2775 3175);
DISPLAY INVISIBLE (2775 3175);
FORCEPROP 1 LAST BODY_TYPE PLUMBING
J 0
(2775 3225);
DISPLAY 0.872340 (2775 3225);
PAINT GREEN (2775 3225);
DISPLAY INVISIBLE (2775 3225);
FORCEPROP 1 LAST HDL_TAP TRUE
J 0
(3100 3050);
DISPLAY 0.872340 (3100 3050);
DISPLAY INVISIBLE (3100 3050);
FORCEPROP 1 LAST PATH I154
J 0
(2773 3175);
DISPLAY 0.872340 (2773 3175);
PAINT GREEN (2773 3175);
DISPLAY INVISIBLE (2773 3175);
FORCEADD OFFPAGE..3
(3875 2150);
FORCEPROP 2 LAST $XR1 113 
J 0
(4209 2150);
DISPLAY 0.638298 (4209 2150);
PAINT MONO (4209 2150);
FORCEPROP 2 LAST $XR0 112 
J 0
(4089 2150);
DISPLAY 0.638298 (4089 2150);
PAINT MONO (4089 2150);
FORCEPROP 2 LAST CDS_LIB standard
J 2
(3875 2150);
DISPLAY INVISIBLE (3875 2150);
FORCEPROP 1 LAST OFFPAGE TRUE
J 0
(4200 2025);
DISPLAY 0.872340 (4200 2025);
DISPLAY INVISIBLE (4200 2025);
FORCEPROP 1 LAST COMMENT_BODY TRUE
J 0
(3825 2050);
DISPLAY 0.872340 (3825 2050);
PAINT GREEN (3825 2050);
DISPLAY INVISIBLE (3825 2050);
FORCEPROP 2 LAST PATH I155
J 0
(4075 2225);
DISPLAY 1.021277 (4075 2225);
DISPLAY INVISIBLE (4075 2225);
FORCEADD OFFPAGE..3
(3875 1550);
FORCEPROP 2 LAST $XR1 113 
J 0
(4209 1550);
DISPLAY 0.638298 (4209 1550);
PAINT MONO (4209 1550);
FORCEPROP 2 LAST $XR0 112 
J 0
(4089 1550);
DISPLAY 0.638298 (4089 1550);
PAINT MONO (4089 1550);
FORCEPROP 2 LAST CDS_LIB standard
J 2
(3875 1550);
DISPLAY INVISIBLE (3875 1550);
FORCEPROP 1 LAST OFFPAGE TRUE
J 0
(4200 1425);
DISPLAY 0.872340 (4200 1425);
DISPLAY INVISIBLE (4200 1425);
FORCEPROP 1 LAST COMMENT_BODY TRUE
J 0
(3825 1450);
DISPLAY 0.872340 (3825 1450);
PAINT GREEN (3825 1450);
DISPLAY INVISIBLE (3825 1450);
FORCEPROP 2 LAST PATH I156
J 0
(4075 1625);
DISPLAY 1.021277 (4075 1625);
DISPLAY INVISIBLE (4075 1625);
FORCEADD OFFPAGE..3
(3875 3300);
FORCEPROP 2 LAST $XR1 113 
J 0
(4209 3300);
DISPLAY 0.638298 (4209 3300);
PAINT MONO (4209 3300);
FORCEPROP 2 LAST $XR0 112 
J 0
(4089 3300);
DISPLAY 0.638298 (4089 3300);
PAINT MONO (4089 3300);
FORCEPROP 2 LAST CDS_LIB standard
J 2
(3875 3300);
DISPLAY INVISIBLE (3875 3300);
FORCEPROP 1 LAST OFFPAGE TRUE
J 0
(4200 3175);
DISPLAY 0.872340 (4200 3175);
DISPLAY INVISIBLE (4200 3175);
FORCEPROP 1 LAST COMMENT_BODY TRUE
J 0
(3825 3200);
DISPLAY 0.872340 (3825 3200);
PAINT GREEN (3825 3200);
DISPLAY INVISIBLE (3825 3200);
FORCEPROP 2 LAST PATH I157
J 0
(4075 3375);
DISPLAY 1.021277 (4075 3375);
DISPLAY INVISIBLE (4075 3375);
FORCEADD OFFPAGE..3
(3875 2700);
FORCEPROP 2 LAST $XR1 113 
J 0
(4209 2700);
DISPLAY 0.638298 (4209 2700);
PAINT MONO (4209 2700);
FORCEPROP 2 LAST $XR0 112 
J 0
(4089 2700);
DISPLAY 0.638298 (4089 2700);
PAINT MONO (4089 2700);
FORCEPROP 2 LAST CDS_LIB standard
J 2
(3875 2700);
DISPLAY INVISIBLE (3875 2700);
FORCEPROP 1 LAST OFFPAGE TRUE
J 0
(4200 2575);
DISPLAY 0.872340 (4200 2575);
DISPLAY INVISIBLE (4200 2575);
FORCEPROP 1 LAST COMMENT_BODY TRUE
J 0
(3825 2600);
DISPLAY 0.872340 (3825 2600);
PAINT GREEN (3825 2600);
DISPLAY INVISIBLE (3825 2600);
FORCEPROP 2 LAST PATH I158
J 0
(4075 2775);
DISPLAY 1.021277 (4075 2775);
DISPLAY INVISIBLE (4075 2775);
FORCEADD TAP..1
(2775 3575);
FORCEPROP 3 LASTPIN (2725 3575) SIG_NAME M_H_CPU1_SA_DQS_DP<4>
J 0
(2735 3585);
DISPLAY 0.659574 (2735 3585);
PAINT MONO (2735 3585);
DISPLAY INVISIBLE (2735 3585);
FORCEPROP 1 LASTPIN (2725 3575) BN 4
J 0
(2713 3583);
DISPLAY 0.680851 (2713 3583);
PAINT GREEN (2713 3583);
FORCEPROP 2 LAST CDS_LIB standard
J 0
(2775 3575);
DISPLAY INVISIBLE (2775 3575);
FORCEPROP 1 LAST BODY_TYPE PLUMBING
J 0
(2775 3625);
DISPLAY 0.872340 (2775 3625);
PAINT GREEN (2775 3625);
DISPLAY INVISIBLE (2775 3625);
FORCEPROP 1 LAST HDL_TAP TRUE
J 0
(3100 3450);
DISPLAY 0.872340 (3100 3450);
DISPLAY INVISIBLE (3100 3450);
FORCEPROP 1 LAST PATH I159
J 0
(2773 3575);
DISPLAY 0.872340 (2773 3575);
PAINT GREEN (2773 3575);
DISPLAY INVISIBLE (2773 3575);
FORCEADD TAP..1
R 2
(-650 125);
FORCEPROP 3 LASTPIN (-600 125) SIG_NAME M_H_CPU1_SB_CB<5>
J 0
(-590 135);
DISPLAY 0.659574 (-590 135);
PAINT MONO (-590 135);
DISPLAY INVISIBLE (-590 135);
FORCEPROP 1 LASTPIN (-600 125) BN 5
J 2
(-588 133);
DISPLAY 0.680851 (-588 133);
PAINT GREEN (-588 133);
FORCEPROP 2 LAST CDS_LIB standard
J 0
(-650 125);
DISPLAY INVISIBLE (-650 125);
FORCEPROP 1 LAST BODY_TYPE PLUMBING
J 2
(-650 175);
DISPLAY 0.872340 (-650 175);
PAINT GREEN (-650 175);
DISPLAY INVISIBLE (-650 175);
FORCEPROP 1 LAST HDL_TAP TRUE
J 2
(-975 0);
DISPLAY 0.872340 (-975 0);
DISPLAY INVISIBLE (-975 0);
FORCEPROP 1 LAST PATH I16
J 2
(-648 125);
DISPLAY 0.872340 (-648 125);
PAINT GREEN (-648 125);
DISPLAY INVISIBLE (-648 125);
FORCEADD TAP..1
(2775 3625);
FORCEPROP 3 LASTPIN (2725 3625) SIG_NAME M_H_CPU1_SA_DQS_DP<5>
J 0
(2735 3635);
DISPLAY 0.659574 (2735 3635);
PAINT MONO (2735 3635);
DISPLAY INVISIBLE (2735 3635);
FORCEPROP 1 LASTPIN (2725 3625) BN 5
J 0
(2713 3633);
DISPLAY 0.680851 (2713 3633);
PAINT GREEN (2713 3633);
FORCEPROP 2 LAST CDS_LIB standard
J 0
(2775 3625);
DISPLAY INVISIBLE (2775 3625);
FORCEPROP 1 LAST BODY_TYPE PLUMBING
J 0
(2775 3675);
DISPLAY 0.872340 (2775 3675);
PAINT GREEN (2775 3675);
DISPLAY INVISIBLE (2775 3675);
FORCEPROP 1 LAST HDL_TAP TRUE
J 0
(3100 3500);
DISPLAY 0.872340 (3100 3500);
DISPLAY INVISIBLE (3100 3500);
FORCEPROP 1 LAST PATH I160
J 0
(2773 3625);
DISPLAY 0.872340 (2773 3625);
PAINT GREEN (2773 3625);
DISPLAY INVISIBLE (2773 3625);
FORCEADD TAP..1
(2775 3675);
FORCEPROP 3 LASTPIN (2725 3675) SIG_NAME M_H_CPU1_SA_DQS_DP<6>
J 0
(2735 3685);
DISPLAY 0.659574 (2735 3685);
PAINT MONO (2735 3685);
DISPLAY INVISIBLE (2735 3685);
FORCEPROP 1 LASTPIN (2725 3675) BN 6
J 0
(2713 3683);
DISPLAY 0.680851 (2713 3683);
PAINT GREEN (2713 3683);
FORCEPROP 2 LAST CDS_LIB standard
J 0
(2775 3675);
DISPLAY INVISIBLE (2775 3675);
FORCEPROP 1 LAST BODY_TYPE PLUMBING
J 0
(2775 3725);
DISPLAY 0.872340 (2775 3725);
PAINT GREEN (2775 3725);
DISPLAY INVISIBLE (2775 3725);
FORCEPROP 1 LAST HDL_TAP TRUE
J 0
(3100 3550);
DISPLAY 0.872340 (3100 3550);
DISPLAY INVISIBLE (3100 3550);
FORCEPROP 1 LAST PATH I161
J 0
(2773 3675);
DISPLAY 0.872340 (2773 3675);
PAINT GREEN (2773 3675);
DISPLAY INVISIBLE (2773 3675);
FORCEADD TAP..1
(2775 3475);
FORCEPROP 3 LASTPIN (2725 3475) SIG_NAME M_H_CPU1_SA_DQS_DP<2>
J 0
(2735 3485);
DISPLAY 0.659574 (2735 3485);
PAINT MONO (2735 3485);
DISPLAY INVISIBLE (2735 3485);
FORCEPROP 1 LASTPIN (2725 3475) BN 2
J 0
(2713 3483);
DISPLAY 0.680851 (2713 3483);
PAINT GREEN (2713 3483);
FORCEPROP 2 LAST CDS_LIB standard
J 0
(2775 3475);
DISPLAY INVISIBLE (2775 3475);
FORCEPROP 1 LAST BODY_TYPE PLUMBING
J 0
(2775 3525);
DISPLAY 0.872340 (2775 3525);
PAINT GREEN (2775 3525);
DISPLAY INVISIBLE (2775 3525);
FORCEPROP 1 LAST HDL_TAP TRUE
J 0
(3100 3350);
DISPLAY 0.872340 (3100 3350);
DISPLAY INVISIBLE (3100 3350);
FORCEPROP 1 LAST PATH I162
J 0
(2773 3475);
DISPLAY 0.872340 (2773 3475);
PAINT GREEN (2773 3475);
DISPLAY INVISIBLE (2773 3475);
FORCEADD TAP..1
(2775 3525);
FORCEPROP 3 LASTPIN (2725 3525) SIG_NAME M_H_CPU1_SA_DQS_DP<3>
J 0
(2735 3535);
DISPLAY 0.659574 (2735 3535);
PAINT MONO (2735 3535);
DISPLAY INVISIBLE (2735 3535);
FORCEPROP 1 LASTPIN (2725 3525) BN 3
J 0
(2713 3533);
DISPLAY 0.680851 (2713 3533);
PAINT GREEN (2713 3533);
FORCEPROP 2 LAST CDS_LIB standard
J 0
(2775 3525);
DISPLAY INVISIBLE (2775 3525);
FORCEPROP 1 LAST BODY_TYPE PLUMBING
J 0
(2775 3575);
DISPLAY 0.872340 (2775 3575);
PAINT GREEN (2775 3575);
DISPLAY INVISIBLE (2775 3575);
FORCEPROP 1 LAST HDL_TAP TRUE
J 0
(3100 3400);
DISPLAY 0.872340 (3100 3400);
DISPLAY INVISIBLE (3100 3400);
FORCEPROP 1 LAST PATH I163
J 0
(2773 3525);
DISPLAY 0.872340 (2773 3525);
PAINT GREEN (2773 3525);
DISPLAY INVISIBLE (2773 3525);
FORCEADD TAP..1
(2775 3425);
FORCEPROP 3 LASTPIN (2725 3425) SIG_NAME M_H_CPU1_SA_DQS_DP<1>
J 0
(2735 3435);
DISPLAY 0.659574 (2735 3435);
PAINT MONO (2735 3435);
DISPLAY INVISIBLE (2735 3435);
FORCEPROP 1 LASTPIN (2725 3425) BN 1
J 0
(2713 3433);
DISPLAY 0.680851 (2713 3433);
PAINT GREEN (2713 3433);
FORCEPROP 2 LAST CDS_LIB standard
J 0
(2775 3425);
DISPLAY INVISIBLE (2775 3425);
FORCEPROP 1 LAST BODY_TYPE PLUMBING
J 0
(2775 3475);
DISPLAY 0.872340 (2775 3475);
PAINT GREEN (2775 3475);
DISPLAY INVISIBLE (2775 3475);
FORCEPROP 1 LAST HDL_TAP TRUE
J 0
(3100 3300);
DISPLAY 0.872340 (3100 3300);
DISPLAY INVISIBLE (3100 3300);
FORCEPROP 1 LAST PATH I164
J 0
(2773 3425);
DISPLAY 0.872340 (2773 3425);
PAINT GREEN (2773 3425);
DISPLAY INVISIBLE (2773 3425);
FORCEADD TAP..1
(2775 3725);
FORCEPROP 3 LASTPIN (2725 3725) SIG_NAME M_H_CPU1_SA_DQS_DP<7>
J 0
(2735 3735);
DISPLAY 0.659574 (2735 3735);
PAINT MONO (2735 3735);
DISPLAY INVISIBLE (2735 3735);
FORCEPROP 1 LASTPIN (2725 3725) BN 7
J 0
(2713 3733);
DISPLAY 0.680851 (2713 3733);
PAINT GREEN (2713 3733);
FORCEPROP 2 LAST CDS_LIB standard
J 0
(2775 3725);
DISPLAY INVISIBLE (2775 3725);
FORCEPROP 1 LAST BODY_TYPE PLUMBING
J 0
(2775 3775);
DISPLAY 0.872340 (2775 3775);
PAINT GREEN (2775 3775);
DISPLAY INVISIBLE (2775 3775);
FORCEPROP 1 LAST HDL_TAP TRUE
J 0
(3100 3600);
DISPLAY 0.872340 (3100 3600);
DISPLAY INVISIBLE (3100 3600);
FORCEPROP 1 LAST PATH I165
J 0
(2773 3725);
DISPLAY 0.872340 (2773 3725);
PAINT GREEN (2773 3725);
DISPLAY INVISIBLE (2773 3725);
FORCEADD TAP..1
(2775 3825);
FORCEPROP 3 LASTPIN (2725 3825) SIG_NAME M_H_CPU1_SA_DQS_DP<9>
J 0
(2735 3835);
DISPLAY 0.659574 (2735 3835);
PAINT MONO (2735 3835);
DISPLAY INVISIBLE (2735 3835);
FORCEPROP 1 LASTPIN (2725 3825) BN 9
J 0
(2713 3833);
DISPLAY 0.680851 (2713 3833);
PAINT GREEN (2713 3833);
FORCEPROP 2 LAST CDS_LIB standard
J 0
(2775 3825);
DISPLAY INVISIBLE (2775 3825);
FORCEPROP 1 LAST BODY_TYPE PLUMBING
J 0
(2775 3875);
DISPLAY 0.872340 (2775 3875);
PAINT GREEN (2775 3875);
DISPLAY INVISIBLE (2775 3875);
FORCEPROP 1 LAST HDL_TAP TRUE
J 0
(3100 3700);
DISPLAY 0.872340 (3100 3700);
DISPLAY INVISIBLE (3100 3700);
FORCEPROP 1 LAST PATH I166
J 0
(2773 3825);
DISPLAY 0.872340 (2773 3825);
PAINT GREEN (2773 3825);
DISPLAY INVISIBLE (2773 3825);
FORCEADD TAP..1
(2775 3775);
FORCEPROP 3 LASTPIN (2725 3775) SIG_NAME M_H_CPU1_SA_DQS_DP<8>
J 0
(2735 3785);
DISPLAY 0.659574 (2735 3785);
PAINT MONO (2735 3785);
DISPLAY INVISIBLE (2735 3785);
FORCEPROP 1 LASTPIN (2725 3775) BN 8
J 0
(2713 3783);
DISPLAY 0.680851 (2713 3783);
PAINT GREEN (2713 3783);
FORCEPROP 2 LAST CDS_LIB standard
J 0
(2775 3775);
DISPLAY INVISIBLE (2775 3775);
FORCEPROP 1 LAST BODY_TYPE PLUMBING
J 0
(2775 3825);
DISPLAY 0.872340 (2775 3825);
PAINT GREEN (2775 3825);
DISPLAY INVISIBLE (2775 3825);
FORCEPROP 1 LAST HDL_TAP TRUE
J 0
(3100 3650);
DISPLAY 0.872340 (3100 3650);
DISPLAY INVISIBLE (3100 3650);
FORCEPROP 1 LAST PATH I167
J 0
(2773 3775);
DISPLAY 0.872340 (2773 3775);
PAINT GREEN (2773 3775);
DISPLAY INVISIBLE (2773 3775);
FORCEADD OFFPAGE..3
(3875 3850);
FORCEPROP 2 LAST $XR1 113 
J 0
(4209 3850);
DISPLAY 0.638298 (4209 3850);
PAINT MONO (4209 3850);
FORCEPROP 2 LAST $XR0 112 
J 0
(4089 3850);
DISPLAY 0.638298 (4089 3850);
PAINT MONO (4089 3850);
FORCEPROP 2 LAST CDS_LIB standard
J 2
(3875 3850);
DISPLAY INVISIBLE (3875 3850);
FORCEPROP 1 LAST OFFPAGE TRUE
J 0
(4200 3725);
DISPLAY 0.872340 (4200 3725);
DISPLAY INVISIBLE (4200 3725);
FORCEPROP 1 LAST COMMENT_BODY TRUE
J 0
(3825 3750);
DISPLAY 0.872340 (3825 3750);
PAINT GREEN (3825 3750);
DISPLAY INVISIBLE (3825 3750);
FORCEPROP 2 LAST PATH I168
J 0
(4075 3925);
DISPLAY 1.021277 (4075 3925);
DISPLAY INVISIBLE (4075 3925);
FORCEADD TAP..1
R 2
(-650 275);
FORCEPROP 3 LASTPIN (-600 275) SIG_NAME M_H_CPU1_SB_DQ<0>
J 0
(-590 285);
DISPLAY 0.659574 (-590 285);
PAINT MONO (-590 285);
DISPLAY INVISIBLE (-590 285);
FORCEPROP 1 LASTPIN (-600 275) BN 0
J 2
(-588 283);
DISPLAY 0.680851 (-588 283);
PAINT GREEN (-588 283);
FORCEPROP 2 LAST CDS_LIB standard
J 0
(-650 275);
DISPLAY INVISIBLE (-650 275);
FORCEPROP 1 LAST BODY_TYPE PLUMBING
J 2
(-650 325);
DISPLAY 0.872340 (-650 325);
PAINT GREEN (-650 325);
DISPLAY INVISIBLE (-650 325);
FORCEPROP 1 LAST HDL_TAP TRUE
J 2
(-975 150);
DISPLAY 0.872340 (-975 150);
DISPLAY INVISIBLE (-975 150);
FORCEPROP 1 LAST PATH I17
J 2
(-648 275);
DISPLAY 0.872340 (-648 275);
PAINT GREEN (-648 275);
DISPLAY INVISIBLE (-648 275);
FORCEADD TAP..1
R 2
(-650 225);
FORCEPROP 3 LASTPIN (-600 225) SIG_NAME M_H_CPU1_SB_CB<7>
J 0
(-590 235);
DISPLAY 0.659574 (-590 235);
PAINT MONO (-590 235);
DISPLAY INVISIBLE (-590 235);
FORCEPROP 1 LASTPIN (-600 225) BN 7
J 2
(-588 233);
DISPLAY 0.680851 (-588 233);
PAINT GREEN (-588 233);
FORCEPROP 2 LAST CDS_LIB standard
J 0
(-650 225);
DISPLAY INVISIBLE (-650 225);
FORCEPROP 1 LAST BODY_TYPE PLUMBING
J 2
(-650 275);
DISPLAY 0.872340 (-650 275);
PAINT GREEN (-650 275);
DISPLAY INVISIBLE (-650 275);
FORCEPROP 1 LAST HDL_TAP TRUE
J 2
(-975 100);
DISPLAY 0.872340 (-975 100);
DISPLAY INVISIBLE (-975 100);
FORCEPROP 1 LAST PATH I18
J 2
(-648 225);
DISPLAY 0.872340 (-648 225);
PAINT GREEN (-648 225);
DISPLAY INVISIBLE (-648 225);
FORCEADD TAP..1
R 2
(-650 325);
FORCEPROP 3 LASTPIN (-600 325) SIG_NAME M_H_CPU1_SB_DQ<1>
J 0
(-590 335);
DISPLAY 0.659574 (-590 335);
PAINT MONO (-590 335);
DISPLAY INVISIBLE (-590 335);
FORCEPROP 1 LASTPIN (-600 325) BN 1
J 2
(-588 333);
DISPLAY 0.680851 (-588 333);
PAINT GREEN (-588 333);
FORCEPROP 2 LAST CDS_LIB standard
J 0
(-650 325);
DISPLAY INVISIBLE (-650 325);
FORCEPROP 1 LAST BODY_TYPE PLUMBING
J 2
(-650 375);
DISPLAY 0.872340 (-650 375);
PAINT GREEN (-650 375);
DISPLAY INVISIBLE (-650 375);
FORCEPROP 1 LAST HDL_TAP TRUE
J 2
(-975 200);
DISPLAY 0.872340 (-975 200);
DISPLAY INVISIBLE (-975 200);
FORCEPROP 1 LAST PATH I19
J 2
(-648 325);
DISPLAY 0.872340 (-648 325);
PAINT GREEN (-648 325);
DISPLAY INVISIBLE (-648 325);
FORCEADD OFFPAGE..2
R 2
(-1675 -300);
FORCEPROP 2 LAST $XR1 113 
J 0
(-2050 -300);
DISPLAY 0.638298 (-2050 -300);
PAINT MONO (-2050 -300);
FORCEPROP 2 LAST $XR0 112 
J 0
(-1930 -300);
DISPLAY 0.638298 (-1930 -300);
PAINT MONO (-1930 -300);
FORCEPROP 2 LAST CDS_LIB standard
J 0
(-1675 -300);
PAINT MONO (-1675 -300);
DISPLAY INVISIBLE (-1675 -300);
FORCEPROP 1 LAST OFFPAGE TRUE
J 2
(-2000 -425);
DISPLAY 0.872340 (-2000 -425);
DISPLAY INVISIBLE (-2000 -425);
FORCEPROP 1 LAST COMMENT_BODY TRUE
J 2
(-1630 -395);
DISPLAY 0.872340 (-1630 -395);
PAINT GREEN (-1630 -395);
DISPLAY INVISIBLE (-1630 -395);
FORCEPROP 2 LAST PATH I2
J 0
(-1625 -225);
DISPLAY 1.021277 (-1625 -225);
DISPLAY INVISIBLE (-1625 -225);
FORCEADD SOCKET4677_AZIF0045P001C01CS..15
(1075 1725);
FORCEPROP 1 LAST PART_NUMBER DGA^7000023
J 0
(-25 4075);
DISPLAY 0.723404 (-25 4075);
PAINT GREEN (-25 4075);
DISPLAY INVISIBLE (-25 4075);
FORCEPROP 2 LAST PART_TYPE SMLF
J 0
(-25 4250);
DISPLAY 1.021277 (-25 4250);
FORCEPROP 1 LAST MATERIAL IO
J 0
(-25 4000);
DISPLAY 0.723404 (-25 4000);
PAINT GREEN (-25 4000);
FORCEPROP 2 LAST VALUE SOCKET4677_AZIF0045-P001C01CS
J 0
(-25 4200);
DISPLAY 1.021277 (-25 4200);
FORCEPROP 1 LAST $LOCATION U1
J 0
(-25 4150);
DISPLAY 0.723404 (-25 4150);
PAINT GREEN (-25 4150);
FORCEPROP 0 LASTPIN (2300 -125) $PN EG48
J 0
(2310 -115);
DISPLAY 0.680851 (2310 -115);
PAINT MONO (2310 -115);
FORCEPROP 0 LASTPIN (2300 -75) $PN EH47
J 0
(2310 -65);
DISPLAY 0.680851 (2310 -65);
PAINT MONO (2310 -65);
FORCEPROP 0 LASTPIN (2300 -375) $PN CY51
J 0
(2310 -365);
DISPLAY 0.680851 (2310 -365);
PAINT MONO (2310 -365);
FORCEPROP 0 LASTPIN (2300 -275) $PN EE48
J 0
(2310 -265);
DISPLAY 0.680851 (2310 -265);
PAINT MONO (2310 -265);
FORCEPROP 0 LASTPIN (2300 -225) $PN ED47
J 0
(2310 -215);
DISPLAY 0.680851 (2310 -215);
PAINT MONO (2310 -215);
FORCEPROP 0 LASTPIN (-150 -375) $PN DH42
J 2
(-160 -365);
DISPLAY 0.680851 (-160 -365);
PAINT MONO (-160 -365);
FORCEPROP 0 LASTPIN (-150 -325) $PN DD42
J 2
(-160 -315);
DISPLAY 0.680851 (-160 -315);
PAINT MONO (-160 -315);
FORCEPROP 0 LASTPIN (-150 -275) $PN DF42
J 2
(-160 -265);
DISPLAY 0.680851 (-160 -265);
PAINT MONO (-160 -265);
FORCEPROP 0 LASTPIN (-150 -225) $PN DB42
J 2
(-160 -215);
DISPLAY 0.680851 (-160 -215);
PAINT MONO (-160 -215);
FORCEPROP 0 LASTPIN (2300 1225) $PN DB49
J 0
(2310 1235);
DISPLAY 0.680851 (2310 1235);
PAINT MONO (2310 1235);
FORCEPROP 0 LASTPIN (2300 1275) $PN DH49
J 0
(2310 1285);
DISPLAY 0.680851 (2310 1285);
PAINT MONO (2310 1285);
FORCEPROP 0 LASTPIN (2300 1325) $PN DC48
J 0
(2310 1335);
DISPLAY 0.680851 (2310 1335);
PAINT MONO (2310 1335);
FORCEPROP 0 LASTPIN (2300 1375) $PN DG48
J 0
(2310 1385);
DISPLAY 0.680851 (2310 1385);
PAINT MONO (2310 1385);
FORCEPROP 0 LASTPIN (2300 1425) $PN DD47
J 0
(2310 1435);
DISPLAY 0.680851 (2310 1435);
PAINT MONO (2310 1435);
FORCEPROP 0 LASTPIN (2300 1475) $PN DF47
J 0
(2310 1485);
DISPLAY 0.680851 (2310 1485);
PAINT MONO (2310 1485);
FORCEPROP 0 LASTPIN (2300 1525) $PN DC41
J 0
(2310 1535);
DISPLAY 0.680851 (2310 1535);
PAINT MONO (2310 1535);
FORCEPROP 0 LASTPIN (-150 2275) $PN DY79
J 2
(-160 2285);
DISPLAY 0.680851 (-160 2285);
PAINT MONO (-160 2285);
FORCEPROP 0 LASTPIN (-150 2325) $PN DT77
J 2
(-160 2335);
DISPLAY 0.680851 (-160 2335);
PAINT MONO (-160 2335);
FORCEPROP 0 LASTPIN (-150 2375) $PN DW78
J 2
(-160 2385);
DISPLAY 0.680851 (-160 2385);
PAINT MONO (-160 2385);
FORCEPROP 0 LASTPIN (-150 2425) $PN DP77
J 2
(-160 2435);
DISPLAY 0.680851 (-160 2435);
PAINT MONO (-160 2435);
FORCEPROP 0 LASTPIN (-150 2475) $PN DK75
J 2
(-160 2485);
DISPLAY 0.680851 (-160 2485);
PAINT MONO (-160 2485);
FORCEPROP 0 LASTPIN (-150 2525) $PN DL74
J 2
(-160 2535);
DISPLAY 0.680851 (-160 2535);
PAINT MONO (-160 2535);
FORCEPROP 0 LASTPIN (-150 2575) $PN DP75
J 2
(-160 2585);
DISPLAY 0.680851 (-160 2585);
PAINT MONO (-160 2585);
FORCEPROP 0 LASTPIN (-150 2625) $PN DN74
J 2
(-160 2635);
DISPLAY 0.680851 (-160 2635);
PAINT MONO (-160 2635);
FORCEPROP 0 LASTPIN (-150 2675) $PN DD75
J 2
(-160 2685);
DISPLAY 0.680851 (-160 2685);
PAINT MONO (-160 2685);
FORCEPROP 0 LASTPIN (-150 2725) $PN DC74
J 2
(-160 2735);
DISPLAY 0.680851 (-160 2735);
PAINT MONO (-160 2735);
FORCEPROP 0 LASTPIN (-150 2775) $PN DF75
J 2
(-160 2785);
DISPLAY 0.680851 (-160 2785);
PAINT MONO (-160 2785);
FORCEPROP 0 LASTPIN (-150 2825) $PN DG74
J 2
(-160 2835);
DISPLAY 0.680851 (-160 2835);
PAINT MONO (-160 2835);
FORCEPROP 0 LASTPIN (-150 2875) $PN DC72
J 2
(-160 2885);
DISPLAY 0.680851 (-160 2885);
PAINT MONO (-160 2885);
FORCEPROP 0 LASTPIN (-150 2925) $PN DD71
J 2
(-160 2935);
DISPLAY 0.680851 (-160 2935);
PAINT MONO (-160 2935);
FORCEPROP 0 LASTPIN (-150 2975) $PN DG72
J 2
(-160 2985);
DISPLAY 0.680851 (-160 2985);
PAINT MONO (-160 2985);
FORCEPROP 0 LASTPIN (-150 3025) $PN DF71
J 2
(-160 3035);
DISPLAY 0.680851 (-160 3035);
PAINT MONO (-160 3035);
FORCEPROP 0 LASTPIN (-150 3075) $PN DD69
J 2
(-160 3085);
DISPLAY 0.680851 (-160 3085);
PAINT MONO (-160 3085);
FORCEPROP 0 LASTPIN (-150 3125) $PN DC68
J 2
(-160 3135);
DISPLAY 0.680851 (-160 3135);
PAINT MONO (-160 3135);
FORCEPROP 0 LASTPIN (-150 3175) $PN DF69
J 2
(-160 3185);
DISPLAY 0.680851 (-160 3185);
PAINT MONO (-160 3185);
FORCEPROP 0 LASTPIN (-150 3225) $PN DG68
J 2
(-160 3235);
DISPLAY 0.680851 (-160 3235);
PAINT MONO (-160 3235);
FORCEPROP 0 LASTPIN (-150 3275) $PN DC66
J 2
(-160 3285);
DISPLAY 0.680851 (-160 3285);
PAINT MONO (-160 3285);
FORCEPROP 0 LASTPIN (-150 3325) $PN DD65
J 2
(-160 3335);
DISPLAY 0.680851 (-160 3335);
PAINT MONO (-160 3335);
FORCEPROP 0 LASTPIN (-150 3375) $PN DG66
J 2
(-160 3385);
DISPLAY 0.680851 (-160 3385);
PAINT MONO (-160 3385);
FORCEPROP 0 LASTPIN (-150 3425) $PN DF65
J 2
(-160 3435);
DISPLAY 0.680851 (-160 3435);
PAINT MONO (-160 3435);
FORCEPROP 0 LASTPIN (-150 3475) $PN DD63
J 2
(-160 3485);
DISPLAY 0.680851 (-160 3485);
PAINT MONO (-160 3485);
FORCEPROP 0 LASTPIN (-150 3525) $PN DC62
J 2
(-160 3535);
DISPLAY 0.680851 (-160 3535);
PAINT MONO (-160 3535);
FORCEPROP 0 LASTPIN (-150 3575) $PN DF63
J 2
(-160 3585);
DISPLAY 0.680851 (-160 3585);
PAINT MONO (-160 3585);
FORCEPROP 0 LASTPIN (-150 3625) $PN DG62
J 2
(-160 3635);
DISPLAY 0.680851 (-160 3635);
PAINT MONO (-160 3635);
FORCEPROP 0 LASTPIN (-150 3675) $PN DC60
J 2
(-160 3685);
DISPLAY 0.680851 (-160 3685);
PAINT MONO (-160 3685);
FORCEPROP 0 LASTPIN (-150 3725) $PN DD59
J 2
(-160 3735);
DISPLAY 0.680851 (-160 3735);
PAINT MONO (-160 3735);
FORCEPROP 0 LASTPIN (-150 3775) $PN DG60
J 2
(-160 3785);
DISPLAY 0.680851 (-160 3785);
PAINT MONO (-160 3785);
FORCEPROP 0 LASTPIN (-150 3825) $PN DF59
J 2
(-160 3835);
DISPLAY 0.680851 (-160 3835);
PAINT MONO (-160 3835);
FORCEPROP 0 LASTPIN (2300 2825) $PN DJ76
J 0
(2310 2835);
DISPLAY 0.680851 (2310 2835);
PAINT MONO (2310 2835);
FORCEPROP 0 LASTPIN (2300 2875) $PN DB73
J 0
(2310 2885);
DISPLAY 0.680851 (2310 2885);
PAINT MONO (2310 2885);
FORCEPROP 0 LASTPIN (2300 2925) $PN DD67
J 0
(2310 2935);
DISPLAY 0.680851 (2310 2935);
PAINT MONO (2310 2935);
FORCEPROP 0 LASTPIN (2300 2975) $PN DD61
J 0
(2310 2985);
DISPLAY 0.680851 (2310 2985);
PAINT MONO (2310 2985);
FORCEPROP 0 LASTPIN (2300 3025) $PN DD55
J 0
(2310 3035);
DISPLAY 0.680851 (2310 3035);
PAINT MONO (2310 3035);
FORCEPROP 0 LASTPIN (2300 3075) $PN DR76
J 0
(2310 3085);
DISPLAY 0.680851 (2310 3085);
PAINT MONO (2310 3085);
FORCEPROP 0 LASTPIN (2300 3125) $PN DH73
J 0
(2310 3135);
DISPLAY 0.680851 (2310 3135);
PAINT MONO (2310 3135);
FORCEPROP 0 LASTPIN (2300 3175) $PN DH67
J 0
(2310 3185);
DISPLAY 0.680851 (2310 3185);
PAINT MONO (2310 3185);
FORCEPROP 0 LASTPIN (2300 3225) $PN DH61
J 0
(2310 3235);
DISPLAY 0.680851 (2310 3235);
PAINT MONO (2310 3235);
FORCEPROP 0 LASTPIN (2300 3275) $PN DH55
J 0
(2310 3285);
DISPLAY 0.680851 (2310 3285);
PAINT MONO (2310 3285);
FORCEPROP 0 LASTPIN (2300 3375) $PN DL76
J 0
(2310 3385);
DISPLAY 0.680851 (2310 3385);
PAINT MONO (2310 3385);
FORCEPROP 0 LASTPIN (2300 3425) $PN DD73
J 0
(2310 3435);
DISPLAY 0.680851 (2310 3435);
PAINT MONO (2310 3435);
FORCEPROP 0 LASTPIN (2300 3475) $PN DB67
J 0
(2310 3485);
DISPLAY 0.680851 (2310 3485);
PAINT MONO (2310 3485);
FORCEPROP 0 LASTPIN (2300 3525) $PN DB61
J 0
(2310 3535);
DISPLAY 0.680851 (2310 3535);
PAINT MONO (2310 3535);
FORCEPROP 0 LASTPIN (2300 3575) $PN DB55
J 0
(2310 3585);
DISPLAY 0.680851 (2310 3585);
PAINT MONO (2310 3585);
FORCEPROP 0 LASTPIN (2300 3625) $PN DN76
J 0
(2310 3635);
DISPLAY 0.680851 (2310 3635);
PAINT MONO (2310 3635);
FORCEPROP 0 LASTPIN (2300 3675) $PN DF73
J 0
(2310 3685);
DISPLAY 0.680851 (2310 3685);
PAINT MONO (2310 3685);
FORCEPROP 0 LASTPIN (2300 3725) $PN DF67
J 0
(2310 3735);
DISPLAY 0.680851 (2310 3735);
PAINT MONO (2310 3735);
FORCEPROP 0 LASTPIN (2300 3775) $PN DF61
J 0
(2310 3785);
DISPLAY 0.680851 (2310 3785);
PAINT MONO (2310 3785);
FORCEPROP 0 LASTPIN (2300 3825) $PN DF55
J 0
(2310 3835);
DISPLAY 0.680851 (2310 3835);
PAINT MONO (2310 3835);
FORCEPROP 0 LASTPIN (-150 1875) $PN DD57
J 2
(-160 1885);
DISPLAY 0.680851 (-160 1885);
PAINT MONO (-160 1885);
FORCEPROP 0 LASTPIN (-150 1925) $PN DC56
J 2
(-160 1935);
DISPLAY 0.680851 (-160 1935);
PAINT MONO (-160 1935);
FORCEPROP 0 LASTPIN (-150 1975) $PN DF57
J 2
(-160 1985);
DISPLAY 0.680851 (-160 1985);
PAINT MONO (-160 1985);
FORCEPROP 0 LASTPIN (-150 2025) $PN DG56
J 2
(-160 2035);
DISPLAY 0.680851 (-160 2035);
PAINT MONO (-160 2035);
FORCEPROP 0 LASTPIN (-150 2075) $PN DC54
J 2
(-160 2085);
DISPLAY 0.680851 (-160 2085);
PAINT MONO (-160 2085);
FORCEPROP 0 LASTPIN (-150 2125) $PN DD53
J 2
(-160 2135);
DISPLAY 0.680851 (-160 2135);
PAINT MONO (-160 2135);
FORCEPROP 0 LASTPIN (-150 2175) $PN DG54
J 2
(-160 2185);
DISPLAY 0.680851 (-160 2185);
PAINT MONO (-160 2185);
FORCEPROP 0 LASTPIN (-150 2225) $PN DF53
J 2
(-160 2235);
DISPLAY 0.680851 (-160 2235);
PAINT MONO (-160 2235);
FORCEPROP 0 LASTPIN (2300 1175) $PN DD40
J 0
(2310 1185);
DISPLAY 0.680851 (2310 1185);
PAINT MONO (2310 1185);
FORCEPROP 0 LASTPIN (2300 725) $PN DF40
J 0
(2310 735);
DISPLAY 0.680851 (2310 735);
PAINT MONO (2310 735);
FORCEPROP 0 LASTPIN (2300 775) $PN DG41
J 0
(2310 785);
DISPLAY 0.680851 (2310 785);
PAINT MONO (2310 785);
FORCEPROP 0 LASTPIN (2300 825) $PN DL41
J 0
(2310 835);
DISPLAY 0.680851 (2310 835);
PAINT MONO (2310 835);
FORCEPROP 0 LASTPIN (2300 875) $PN DN41
J 0
(2310 885);
DISPLAY 0.680851 (2310 885);
PAINT MONO (2310 885);
FORCEPROP 0 LASTPIN (2300 925) $PN DK40
J 0
(2310 935);
DISPLAY 0.680851 (2310 935);
PAINT MONO (2310 935);
FORCEPROP 0 LASTPIN (2300 975) $PN DP40
J 0
(2310 985);
DISPLAY 0.680851 (2310 985);
PAINT MONO (2310 985);
FORCEPROP 0 LASTPIN (2300 1025) $PN DJ39
J 0
(2310 1035);
DISPLAY 0.680851 (2310 1035);
PAINT MONO (2310 1035);
FORCEPROP 0 LASTPIN (-150 275) $PN DD32
J 2
(-160 285);
DISPLAY 0.680851 (-160 285);
PAINT MONO (-160 285);
FORCEPROP 0 LASTPIN (-150 325) $PN DC31
J 2
(-160 335);
DISPLAY 0.680851 (-160 335);
PAINT MONO (-160 335);
FORCEPROP 0 LASTPIN (-150 375) $PN DF32
J 2
(-160 385);
DISPLAY 0.680851 (-160 385);
PAINT MONO (-160 385);
FORCEPROP 0 LASTPIN (-150 425) $PN DG31
J 2
(-160 435);
DISPLAY 0.680851 (-160 435);
PAINT MONO (-160 435);
FORCEPROP 0 LASTPIN (-150 475) $PN DC29
J 2
(-160 485);
DISPLAY 0.680851 (-160 485);
PAINT MONO (-160 485);
FORCEPROP 0 LASTPIN (-150 525) $PN DF28
J 2
(-160 535);
DISPLAY 0.680851 (-160 535);
PAINT MONO (-160 535);
FORCEPROP 0 LASTPIN (-150 575) $PN DG29
J 2
(-160 585);
DISPLAY 0.680851 (-160 585);
PAINT MONO (-160 585);
FORCEPROP 0 LASTPIN (-150 625) $PN DD28
J 2
(-160 635);
DISPLAY 0.680851 (-160 635);
PAINT MONO (-160 635);
FORCEPROP 0 LASTPIN (-150 675) $PN DD26
J 2
(-160 685);
DISPLAY 0.680851 (-160 685);
PAINT MONO (-160 685);
FORCEPROP 0 LASTPIN (-150 725) $PN DC25
J 2
(-160 735);
DISPLAY 0.680851 (-160 735);
PAINT MONO (-160 735);
FORCEPROP 0 LASTPIN (-150 775) $PN DF26
J 2
(-160 785);
DISPLAY 0.680851 (-160 785);
PAINT MONO (-160 785);
FORCEPROP 0 LASTPIN (-150 825) $PN DG25
J 2
(-160 835);
DISPLAY 0.680851 (-160 835);
PAINT MONO (-160 835);
FORCEPROP 0 LASTPIN (-150 875) $PN DC23
J 2
(-160 885);
DISPLAY 0.680851 (-160 885);
PAINT MONO (-160 885);
FORCEPROP 0 LASTPIN (-150 925) $PN DD22
J 2
(-160 935);
DISPLAY 0.680851 (-160 935);
PAINT MONO (-160 935);
FORCEPROP 0 LASTPIN (-150 975) $PN DG23
J 2
(-160 985);
DISPLAY 0.680851 (-160 985);
PAINT MONO (-160 985);
FORCEPROP 0 LASTPIN (-150 1025) $PN DF22
J 2
(-160 1035);
DISPLAY 0.680851 (-160 1035);
PAINT MONO (-160 1035);
FORCEPROP 0 LASTPIN (-150 1075) $PN DL23
J 2
(-160 1085);
DISPLAY 0.680851 (-160 1085);
PAINT MONO (-160 1085);
FORCEPROP 0 LASTPIN (-150 1125) $PN DK22
J 2
(-160 1135);
DISPLAY 0.680851 (-160 1135);
PAINT MONO (-160 1135);
FORCEPROP 0 LASTPIN (-150 1175) $PN DN23
J 2
(-160 1185);
DISPLAY 0.680851 (-160 1185);
PAINT MONO (-160 1185);
FORCEPROP 0 LASTPIN (-150 1225) $PN DP22
J 2
(-160 1235);
DISPLAY 0.680851 (-160 1235);
PAINT MONO (-160 1235);
FORCEPROP 0 LASTPIN (-150 1275) $PN DK20
J 2
(-160 1285);
DISPLAY 0.680851 (-160 1285);
PAINT MONO (-160 1285);
FORCEPROP 0 LASTPIN (-150 1325) $PN DL19
J 2
(-160 1335);
DISPLAY 0.680851 (-160 1335);
PAINT MONO (-160 1335);
FORCEPROP 0 LASTPIN (-150 1375) $PN DP20
J 2
(-160 1385);
DISPLAY 0.680851 (-160 1385);
PAINT MONO (-160 1385);
FORCEPROP 0 LASTPIN (-150 1425) $PN DN19
J 2
(-160 1435);
DISPLAY 0.680851 (-160 1435);
PAINT MONO (-160 1435);
FORCEPROP 0 LASTPIN (-150 1475) $PN DD20
J 2
(-160 1485);
DISPLAY 0.680851 (-160 1485);
PAINT MONO (-160 1485);
FORCEPROP 0 LASTPIN (-150 1525) $PN DC19
J 2
(-160 1535);
DISPLAY 0.680851 (-160 1535);
PAINT MONO (-160 1535);
FORCEPROP 0 LASTPIN (-150 1575) $PN DF20
J 2
(-160 1585);
DISPLAY 0.680851 (-160 1585);
PAINT MONO (-160 1585);
FORCEPROP 0 LASTPIN (-150 1625) $PN DG19
J 2
(-160 1635);
DISPLAY 0.680851 (-160 1635);
PAINT MONO (-160 1635);
FORCEPROP 0 LASTPIN (-150 1675) $PN DG17
J 2
(-160 1685);
DISPLAY 0.680851 (-160 1685);
PAINT MONO (-160 1685);
FORCEPROP 0 LASTPIN (-150 1725) $PN DA17
J 2
(-160 1735);
DISPLAY 0.680851 (-160 1735);
PAINT MONO (-160 1735);
FORCEPROP 0 LASTPIN (-150 1775) $PN DJ17
J 2
(-160 1785);
DISPLAY 0.680851 (-160 1785);
PAINT MONO (-160 1785);
FORCEPROP 0 LASTPIN (-150 1825) $PN DC17
J 2
(-160 1835);
DISPLAY 0.680851 (-160 1835);
PAINT MONO (-160 1835);
FORCEPROP 0 LASTPIN (2300 1675) $PN DD30
J 0
(2310 1685);
DISPLAY 0.680851 (2310 1685);
PAINT MONO (2310 1685);
FORCEPROP 0 LASTPIN (2300 1725) $PN DD24
J 0
(2310 1735);
DISPLAY 0.680851 (2310 1735);
PAINT MONO (2310 1735);
FORCEPROP 0 LASTPIN (2300 1775) $PN DL21
J 0
(2310 1785);
DISPLAY 0.680851 (2310 1785);
PAINT MONO (2310 1785);
FORCEPROP 0 LASTPIN (2300 1825) $PN DB18
J 0
(2310 1835);
DISPLAY 0.680851 (2310 1835);
PAINT MONO (2310 1835);
FORCEPROP 0 LASTPIN (2300 1875) $PN DH36
J 0
(2310 1885);
DISPLAY 0.680851 (2310 1885);
PAINT MONO (2310 1885);
FORCEPROP 0 LASTPIN (2300 1925) $PN DH30
J 0
(2310 1935);
DISPLAY 0.680851 (2310 1935);
PAINT MONO (2310 1935);
FORCEPROP 0 LASTPIN (2300 1975) $PN DH24
J 0
(2310 1985);
DISPLAY 0.680851 (2310 1985);
PAINT MONO (2310 1985);
FORCEPROP 0 LASTPIN (2300 2025) $PN DR21
J 0
(2310 2035);
DISPLAY 0.680851 (2310 2035);
PAINT MONO (2310 2035);
FORCEPROP 0 LASTPIN (2300 2075) $PN DF18
J 0
(2310 2085);
DISPLAY 0.680851 (2310 2085);
PAINT MONO (2310 2085);
FORCEPROP 0 LASTPIN (2300 2125) $PN DD36
J 0
(2310 2135);
DISPLAY 0.680851 (2310 2135);
PAINT MONO (2310 2135);
FORCEPROP 0 LASTPIN (2300 2225) $PN DB30
J 0
(2310 2235);
DISPLAY 0.680851 (2310 2235);
PAINT MONO (2310 2235);
FORCEPROP 0 LASTPIN (2300 2275) $PN DB24
J 0
(2310 2285);
DISPLAY 0.680851 (2310 2285);
PAINT MONO (2310 2285);
FORCEPROP 0 LASTPIN (2300 2325) $PN DJ21
J 0
(2310 2335);
DISPLAY 0.680851 (2310 2335);
PAINT MONO (2310 2335);
FORCEPROP 0 LASTPIN (2300 2375) $PN DD18
J 0
(2310 2385);
DISPLAY 0.680851 (2310 2385);
PAINT MONO (2310 2385);
FORCEPROP 0 LASTPIN (2300 2425) $PN DF36
J 0
(2310 2435);
DISPLAY 0.680851 (2310 2435);
PAINT MONO (2310 2435);
FORCEPROP 0 LASTPIN (2300 2475) $PN DF30
J 0
(2310 2485);
DISPLAY 0.680851 (2310 2485);
PAINT MONO (2310 2485);
FORCEPROP 0 LASTPIN (2300 2525) $PN DF24
J 0
(2310 2535);
DISPLAY 0.680851 (2310 2535);
PAINT MONO (2310 2535);
FORCEPROP 0 LASTPIN (2300 2575) $PN DN21
J 0
(2310 2585);
DISPLAY 0.680851 (2310 2585);
PAINT MONO (2310 2585);
FORCEPROP 0 LASTPIN (2300 2625) $PN DH18
J 0
(2310 2635);
DISPLAY 0.680851 (2310 2635);
PAINT MONO (2310 2635);
FORCEPROP 0 LASTPIN (2300 2675) $PN DB36
J 0
(2310 2685);
DISPLAY 0.680851 (2310 2685);
PAINT MONO (2310 2685);
FORCEPROP 0 LASTPIN (-150 -125) $PN DC35
J 2
(-160 -115);
DISPLAY 0.680851 (-160 -115);
PAINT MONO (-160 -115);
FORCEPROP 0 LASTPIN (-150 -75) $PN DD34
J 2
(-160 -65);
DISPLAY 0.680851 (-160 -65);
PAINT MONO (-160 -65);
FORCEPROP 0 LASTPIN (-150 -25) $PN DG35
J 2
(-160 -15);
DISPLAY 0.680851 (-160 -15);
PAINT MONO (-160 -15);
FORCEPROP 0 LASTPIN (-150 25) $PN DF34
J 2
(-160 35);
DISPLAY 0.680851 (-160 35);
PAINT MONO (-160 35);
FORCEPROP 0 LASTPIN (-150 75) $PN DF38
J 2
(-160 85);
DISPLAY 0.680851 (-160 85);
PAINT MONO (-160 85);
FORCEPROP 0 LASTPIN (-150 125) $PN DG37
J 2
(-160 135);
DISPLAY 0.680851 (-160 135);
PAINT MONO (-160 135);
FORCEPROP 0 LASTPIN (-150 175) $PN DD38
J 2
(-160 185);
DISPLAY 0.680851 (-160 185);
PAINT MONO (-160 185);
FORCEPROP 0 LASTPIN (-150 225) $PN DC37
J 2
(-160 235);
DISPLAY 0.680851 (-160 235);
PAINT MONO (-160 235);
FORCEPROP 0 LASTPIN (2300 675) $PN DR39
J 0
(2310 685);
DISPLAY 0.680851 (2310 685);
PAINT MONO (2310 685);
FORCEPROP 0 LASTPIN (2300 375) $PN DF51
J 0
(2310 385);
DISPLAY 0.680851 (2310 385);
PAINT MONO (2310 385);
FORCEPROP 0 LASTPIN (2300 425) $PN DG50
J 0
(2310 435);
DISPLAY 0.680851 (2310 435);
PAINT MONO (2310 435);
FORCEPROP 0 LASTPIN (2300 475) $PN DD51
J 0
(2310 485);
DISPLAY 0.680851 (2310 485);
PAINT MONO (2310 485);
FORCEPROP 0 LASTPIN (2300 525) $PN DC50
J 0
(2310 535);
DISPLAY 0.680851 (2310 535);
PAINT MONO (2310 535);
FORCEPROP 0 LASTPIN (2300 75) $PN DL37
J 0
(2310 85);
DISPLAY 0.680851 (2310 85);
PAINT MONO (2310 85);
FORCEPROP 0 LASTPIN (2300 125) $PN DN37
J 0
(2310 135);
DISPLAY 0.680851 (2310 135);
PAINT MONO (2310 135);
FORCEPROP 0 LASTPIN (2300 175) $PN DK38
J 0
(2310 185);
DISPLAY 0.680851 (2310 185);
PAINT MONO (2310 185);
FORCEPROP 0 LASTPIN (2300 225) $PN DP38
J 0
(2310 235);
DISPLAY 0.680851 (2310 235);
PAINT MONO (2310 235);
FORCEPROP 2 LAST CDS_LIB pure_quanta
J 0
(1075 1725);
DISPLAY INVISIBLE (1075 1725);
FORCEPROP 1 LAST NEEDS_NO_SIZE TRUE
J 0
(1075 1725);
DISPLAY 0.723404 (1075 1725);
PAINT GREEN (1075 1725);
DISPLAY INVISIBLE (1075 1725);
FORCEPROP 1 LAST CDS_LMAN_SYM_OUTLINE -1100,2250,1050,-2250
J 0
(1075 1725);
DISPLAY 0.468085 (1075 1725);
PAINT GREEN (1075 1725);
DISPLAY INVISIBLE (1075 1725);
FORCEPROP 2 LAST CDS_LOCATION U1
J 0
(-25 4300);
DISPLAY 1.021277 (-25 4300);
DISPLAY INVISIBLE (-25 4300);
FORCEPROP 0 LAST $SEC 15
J 0
(-25 4300);
DISPLAY 0.680851 (-25 4300);
PAINT MONO (-25 4300);
DISPLAY INVISIBLE (-25 4300);
FORCEPROP 2 LAST CDS_SEC 15
J 0
(-25 4300);
DISPLAY 1.021277 (-25 4300);
DISPLAY INVISIBLE (-25 4300);
FORCEPROP 1 LAST PATH I20
J 0
(1075 1725);
DISPLAY 0.723404 (1075 1725);
PAINT GREEN (1075 1725);
DISPLAY INVISIBLE (1075 1725);
FORCEADD TAP..1
R 2
(-650 425);
FORCEPROP 3 LASTPIN (-600 425) SIG_NAME M_H_CPU1_SB_DQ<3>
J 0
(-590 435);
DISPLAY 0.659574 (-590 435);
PAINT MONO (-590 435);
DISPLAY INVISIBLE (-590 435);
FORCEPROP 1 LASTPIN (-600 425) BN 3
J 2
(-588 433);
DISPLAY 0.680851 (-588 433);
PAINT GREEN (-588 433);
FORCEPROP 2 LAST CDS_LIB standard
J 0
(-650 425);
DISPLAY INVISIBLE (-650 425);
FORCEPROP 1 LAST BODY_TYPE PLUMBING
J 2
(-650 475);
DISPLAY 0.872340 (-650 475);
PAINT GREEN (-650 475);
DISPLAY INVISIBLE (-650 475);
FORCEPROP 1 LAST HDL_TAP TRUE
J 2
(-975 300);
DISPLAY 0.872340 (-975 300);
DISPLAY INVISIBLE (-975 300);
FORCEPROP 1 LAST PATH I21
J 2
(-648 425);
DISPLAY 0.872340 (-648 425);
PAINT GREEN (-648 425);
DISPLAY INVISIBLE (-648 425);
FORCEADD TAP..1
R 2
(-650 375);
FORCEPROP 3 LASTPIN (-600 375) SIG_NAME M_H_CPU1_SB_DQ<2>
J 0
(-590 385);
DISPLAY 0.659574 (-590 385);
PAINT MONO (-590 385);
DISPLAY INVISIBLE (-590 385);
FORCEPROP 1 LASTPIN (-600 375) BN 2
J 2
(-588 383);
DISPLAY 0.680851 (-588 383);
PAINT GREEN (-588 383);
FORCEPROP 2 LAST CDS_LIB standard
J 0
(-650 375);
DISPLAY INVISIBLE (-650 375);
FORCEPROP 1 LAST BODY_TYPE PLUMBING
J 2
(-650 425);
DISPLAY 0.872340 (-650 425);
PAINT GREEN (-650 425);
DISPLAY INVISIBLE (-650 425);
FORCEPROP 1 LAST HDL_TAP TRUE
J 2
(-975 250);
DISPLAY 0.872340 (-975 250);
DISPLAY INVISIBLE (-975 250);
FORCEPROP 1 LAST PATH I22
J 2
(-648 375);
DISPLAY 0.872340 (-648 375);
PAINT GREEN (-648 375);
DISPLAY INVISIBLE (-648 375);
FORCEADD TAP..1
R 2
(-650 475);
FORCEPROP 3 LASTPIN (-600 475) SIG_NAME M_H_CPU1_SB_DQ<4>
J 0
(-590 485);
DISPLAY 0.659574 (-590 485);
PAINT MONO (-590 485);
DISPLAY INVISIBLE (-590 485);
FORCEPROP 1 LASTPIN (-600 475) BN 4
J 2
(-588 483);
DISPLAY 0.680851 (-588 483);
PAINT GREEN (-588 483);
FORCEPROP 2 LAST CDS_LIB standard
J 0
(-650 475);
DISPLAY INVISIBLE (-650 475);
FORCEPROP 1 LAST BODY_TYPE PLUMBING
J 2
(-650 525);
DISPLAY 0.872340 (-650 525);
PAINT GREEN (-650 525);
DISPLAY INVISIBLE (-650 525);
FORCEPROP 1 LAST HDL_TAP TRUE
J 2
(-975 350);
DISPLAY 0.872340 (-975 350);
DISPLAY INVISIBLE (-975 350);
FORCEPROP 1 LAST PATH I23
J 2
(-648 475);
DISPLAY 0.872340 (-648 475);
PAINT GREEN (-648 475);
DISPLAY INVISIBLE (-648 475);
FORCEADD TAP..1
R 2
(-650 575);
FORCEPROP 3 LASTPIN (-600 575) SIG_NAME M_H_CPU1_SB_DQ<6>
J 0
(-590 585);
DISPLAY 0.659574 (-590 585);
PAINT MONO (-590 585);
DISPLAY INVISIBLE (-590 585);
FORCEPROP 1 LASTPIN (-600 575) BN 6
J 2
(-588 583);
DISPLAY 0.680851 (-588 583);
PAINT GREEN (-588 583);
FORCEPROP 2 LAST CDS_LIB standard
J 0
(-650 575);
DISPLAY INVISIBLE (-650 575);
FORCEPROP 1 LAST BODY_TYPE PLUMBING
J 2
(-650 625);
DISPLAY 0.872340 (-650 625);
PAINT GREEN (-650 625);
DISPLAY INVISIBLE (-650 625);
FORCEPROP 1 LAST HDL_TAP TRUE
J 2
(-975 450);
DISPLAY 0.872340 (-975 450);
DISPLAY INVISIBLE (-975 450);
FORCEPROP 1 LAST PATH I24
J 2
(-648 575);
DISPLAY 0.872340 (-648 575);
PAINT GREEN (-648 575);
DISPLAY INVISIBLE (-648 575);
FORCEADD TAP..1
R 2
(-650 525);
FORCEPROP 3 LASTPIN (-600 525) SIG_NAME M_H_CPU1_SB_DQ<5>
J 0
(-590 535);
DISPLAY 0.659574 (-590 535);
PAINT MONO (-590 535);
DISPLAY INVISIBLE (-590 535);
FORCEPROP 1 LASTPIN (-600 525) BN 5
J 2
(-588 533);
DISPLAY 0.680851 (-588 533);
PAINT GREEN (-588 533);
FORCEPROP 2 LAST CDS_LIB standard
J 0
(-650 525);
DISPLAY INVISIBLE (-650 525);
FORCEPROP 1 LAST BODY_TYPE PLUMBING
J 2
(-650 575);
DISPLAY 0.872340 (-650 575);
PAINT GREEN (-650 575);
DISPLAY INVISIBLE (-650 575);
FORCEPROP 1 LAST HDL_TAP TRUE
J 2
(-975 400);
DISPLAY 0.872340 (-975 400);
DISPLAY INVISIBLE (-975 400);
FORCEPROP 1 LAST PATH I25
J 2
(-648 525);
DISPLAY 0.872340 (-648 525);
PAINT GREEN (-648 525);
DISPLAY INVISIBLE (-648 525);
FORCEADD TAP..1
R 2
(-650 675);
FORCEPROP 3 LASTPIN (-600 675) SIG_NAME M_H_CPU1_SB_DQ<8>
J 0
(-590 685);
DISPLAY 0.659574 (-590 685);
PAINT MONO (-590 685);
DISPLAY INVISIBLE (-590 685);
FORCEPROP 1 LASTPIN (-600 675) BN 8
J 2
(-588 683);
DISPLAY 0.680851 (-588 683);
PAINT GREEN (-588 683);
FORCEPROP 2 LAST CDS_LIB standard
J 0
(-650 675);
DISPLAY INVISIBLE (-650 675);
FORCEPROP 1 LAST BODY_TYPE PLUMBING
J 2
(-650 725);
DISPLAY 0.872340 (-650 725);
PAINT GREEN (-650 725);
DISPLAY INVISIBLE (-650 725);
FORCEPROP 1 LAST HDL_TAP TRUE
J 2
(-975 550);
DISPLAY 0.872340 (-975 550);
DISPLAY INVISIBLE (-975 550);
FORCEPROP 1 LAST PATH I26
J 2
(-648 675);
DISPLAY 0.872340 (-648 675);
PAINT GREEN (-648 675);
DISPLAY INVISIBLE (-648 675);
FORCEADD TAP..1
R 2
(-650 625);
FORCEPROP 3 LASTPIN (-600 625) SIG_NAME M_H_CPU1_SB_DQ<7>
J 0
(-590 635);
DISPLAY 0.659574 (-590 635);
PAINT MONO (-590 635);
DISPLAY INVISIBLE (-590 635);
FORCEPROP 1 LASTPIN (-600 625) BN 7
J 2
(-588 633);
DISPLAY 0.680851 (-588 633);
PAINT GREEN (-588 633);
FORCEPROP 2 LAST CDS_LIB standard
J 0
(-650 625);
DISPLAY INVISIBLE (-650 625);
FORCEPROP 1 LAST BODY_TYPE PLUMBING
J 2
(-650 675);
DISPLAY 0.872340 (-650 675);
PAINT GREEN (-650 675);
DISPLAY INVISIBLE (-650 675);
FORCEPROP 1 LAST HDL_TAP TRUE
J 2
(-975 500);
DISPLAY 0.872340 (-975 500);
DISPLAY INVISIBLE (-975 500);
FORCEPROP 1 LAST PATH I27
J 2
(-648 625);
DISPLAY 0.872340 (-648 625);
PAINT GREEN (-648 625);
DISPLAY INVISIBLE (-648 625);
FORCEADD TAP..1
R 2
(-650 725);
FORCEPROP 3 LASTPIN (-600 725) SIG_NAME M_H_CPU1_SB_DQ<9>
J 0
(-590 735);
DISPLAY 0.659574 (-590 735);
PAINT MONO (-590 735);
DISPLAY INVISIBLE (-590 735);
FORCEPROP 1 LASTPIN (-600 725) BN 9
J 2
(-588 733);
DISPLAY 0.680851 (-588 733);
PAINT GREEN (-588 733);
FORCEPROP 2 LAST CDS_LIB standard
J 0
(-650 725);
DISPLAY INVISIBLE (-650 725);
FORCEPROP 1 LAST BODY_TYPE PLUMBING
J 2
(-650 775);
DISPLAY 0.872340 (-650 775);
PAINT GREEN (-650 775);
DISPLAY INVISIBLE (-650 775);
FORCEPROP 1 LAST HDL_TAP TRUE
J 2
(-975 600);
DISPLAY 0.872340 (-975 600);
DISPLAY INVISIBLE (-975 600);
FORCEPROP 1 LAST PATH I28
J 2
(-648 725);
DISPLAY 0.872340 (-648 725);
PAINT GREEN (-648 725);
DISPLAY INVISIBLE (-648 725);
FORCEADD TAP..1
R 2
(-650 775);
FORCEPROP 3 LASTPIN (-600 775) SIG_NAME M_H_CPU1_SB_DQ<10>
J 0
(-590 785);
DISPLAY 0.659574 (-590 785);
PAINT MONO (-590 785);
DISPLAY INVISIBLE (-590 785);
FORCEPROP 1 LASTPIN (-600 775) BN 10
J 2
(-588 783);
DISPLAY 0.680851 (-588 783);
PAINT GREEN (-588 783);
FORCEPROP 2 LAST CDS_LIB standard
J 0
(-650 775);
DISPLAY INVISIBLE (-650 775);
FORCEPROP 1 LAST BODY_TYPE PLUMBING
J 2
(-650 825);
DISPLAY 0.872340 (-650 825);
PAINT GREEN (-650 825);
DISPLAY INVISIBLE (-650 825);
FORCEPROP 1 LAST HDL_TAP TRUE
J 2
(-975 650);
DISPLAY 0.872340 (-975 650);
DISPLAY INVISIBLE (-975 650);
FORCEPROP 1 LAST PATH I29
J 2
(-648 775);
DISPLAY 0.872340 (-648 775);
PAINT GREEN (-648 775);
DISPLAY INVISIBLE (-648 775);
FORCEADD OFFPAGE..3
R 2
(-1675 250);
FORCEPROP 2 LAST $XR1 113 
J 0
(-2105 250);
DISPLAY 0.638298 (-2105 250);
PAINT MONO (-2105 250);
FORCEPROP 2 LAST $XR0 112 
J 0
(-1985 250);
DISPLAY 0.638298 (-1985 250);
PAINT MONO (-1985 250);
FORCEPROP 2 LAST CDS_LIB standard
J 0
(-1675 250);
DISPLAY INVISIBLE (-1675 250);
FORCEPROP 1 LAST OFFPAGE TRUE
J 2
(-2000 125);
DISPLAY 0.872340 (-2000 125);
DISPLAY INVISIBLE (-2000 125);
FORCEPROP 1 LAST COMMENT_BODY TRUE
J 2
(-1625 150);
DISPLAY 0.872340 (-1625 150);
PAINT GREEN (-1625 150);
DISPLAY INVISIBLE (-1625 150);
FORCEPROP 2 LAST PATH I3
J 0
(-1625 325);
DISPLAY 1.021277 (-1625 325);
DISPLAY INVISIBLE (-1625 325);
FORCEADD TAP..1
R 2
(-650 825);
FORCEPROP 3 LASTPIN (-600 825) SIG_NAME M_H_CPU1_SB_DQ<11>
J 0
(-590 835);
DISPLAY 0.659574 (-590 835);
PAINT MONO (-590 835);
DISPLAY INVISIBLE (-590 835);
FORCEPROP 1 LASTPIN (-600 825) BN 11
J 2
(-588 833);
DISPLAY 0.680851 (-588 833);
PAINT GREEN (-588 833);
FORCEPROP 2 LAST CDS_LIB standard
J 0
(-650 825);
DISPLAY INVISIBLE (-650 825);
FORCEPROP 1 LAST BODY_TYPE PLUMBING
J 2
(-650 875);
DISPLAY 0.872340 (-650 875);
PAINT GREEN (-650 875);
DISPLAY INVISIBLE (-650 875);
FORCEPROP 1 LAST HDL_TAP TRUE
J 2
(-975 700);
DISPLAY 0.872340 (-975 700);
DISPLAY INVISIBLE (-975 700);
FORCEPROP 1 LAST PATH I30
J 2
(-648 825);
DISPLAY 0.872340 (-648 825);
PAINT GREEN (-648 825);
DISPLAY INVISIBLE (-648 825);
FORCEADD TAP..1
R 2
(-650 925);
FORCEPROP 3 LASTPIN (-600 925) SIG_NAME M_H_CPU1_SB_DQ<13>
J 0
(-590 935);
DISPLAY 0.659574 (-590 935);
PAINT MONO (-590 935);
DISPLAY INVISIBLE (-590 935);
FORCEPROP 1 LASTPIN (-600 925) BN 13
J 2
(-588 933);
DISPLAY 0.680851 (-588 933);
PAINT GREEN (-588 933);
FORCEPROP 2 LAST CDS_LIB standard
J 0
(-650 925);
DISPLAY INVISIBLE (-650 925);
FORCEPROP 1 LAST BODY_TYPE PLUMBING
J 2
(-650 975);
DISPLAY 0.872340 (-650 975);
PAINT GREEN (-650 975);
DISPLAY INVISIBLE (-650 975);
FORCEPROP 1 LAST HDL_TAP TRUE
J 2
(-975 800);
DISPLAY 0.872340 (-975 800);
DISPLAY INVISIBLE (-975 800);
FORCEPROP 1 LAST PATH I31
J 2
(-648 925);
DISPLAY 0.872340 (-648 925);
PAINT GREEN (-648 925);
DISPLAY INVISIBLE (-648 925);
FORCEADD TAP..1
R 2
(-650 875);
FORCEPROP 3 LASTPIN (-600 875) SIG_NAME M_H_CPU1_SB_DQ<12>
J 0
(-590 885);
DISPLAY 0.659574 (-590 885);
PAINT MONO (-590 885);
DISPLAY INVISIBLE (-590 885);
FORCEPROP 1 LASTPIN (-600 875) BN 12
J 2
(-588 883);
DISPLAY 0.680851 (-588 883);
PAINT GREEN (-588 883);
FORCEPROP 2 LAST CDS_LIB standard
J 0
(-650 875);
DISPLAY INVISIBLE (-650 875);
FORCEPROP 1 LAST BODY_TYPE PLUMBING
J 2
(-650 925);
DISPLAY 0.872340 (-650 925);
PAINT GREEN (-650 925);
DISPLAY INVISIBLE (-650 925);
FORCEPROP 1 LAST HDL_TAP TRUE
J 2
(-975 750);
DISPLAY 0.872340 (-975 750);
DISPLAY INVISIBLE (-975 750);
FORCEPROP 1 LAST PATH I32
J 2
(-648 875);
DISPLAY 0.872340 (-648 875);
PAINT GREEN (-648 875);
DISPLAY INVISIBLE (-648 875);
FORCEADD TAP..1
R 2
(-650 975);
FORCEPROP 3 LASTPIN (-600 975) SIG_NAME M_H_CPU1_SB_DQ<14>
J 0
(-590 985);
DISPLAY 0.659574 (-590 985);
PAINT MONO (-590 985);
DISPLAY INVISIBLE (-590 985);
FORCEPROP 1 LASTPIN (-600 975) BN 14
J 2
(-588 983);
DISPLAY 0.680851 (-588 983);
PAINT GREEN (-588 983);
FORCEPROP 2 LAST CDS_LIB standard
J 0
(-650 975);
DISPLAY INVISIBLE (-650 975);
FORCEPROP 1 LAST BODY_TYPE PLUMBING
J 2
(-650 1025);
DISPLAY 0.872340 (-650 1025);
PAINT GREEN (-650 1025);
DISPLAY INVISIBLE (-650 1025);
FORCEPROP 1 LAST HDL_TAP TRUE
J 2
(-975 850);
DISPLAY 0.872340 (-975 850);
DISPLAY INVISIBLE (-975 850);
FORCEPROP 1 LAST PATH I33
J 2
(-648 975);
DISPLAY 0.872340 (-648 975);
PAINT GREEN (-648 975);
DISPLAY INVISIBLE (-648 975);
FORCEADD TAP..1
R 2
(-650 1025);
FORCEPROP 3 LASTPIN (-600 1025) SIG_NAME M_H_CPU1_SB_DQ<15>
J 0
(-590 1035);
DISPLAY 0.659574 (-590 1035);
PAINT MONO (-590 1035);
DISPLAY INVISIBLE (-590 1035);
FORCEPROP 1 LASTPIN (-600 1025) BN 15
J 2
(-588 1033);
DISPLAY 0.680851 (-588 1033);
PAINT GREEN (-588 1033);
FORCEPROP 2 LAST CDS_LIB standard
J 0
(-650 1025);
DISPLAY INVISIBLE (-650 1025);
FORCEPROP 1 LAST BODY_TYPE PLUMBING
J 2
(-650 1075);
DISPLAY 0.872340 (-650 1075);
PAINT GREEN (-650 1075);
DISPLAY INVISIBLE (-650 1075);
FORCEPROP 1 LAST HDL_TAP TRUE
J 2
(-975 900);
DISPLAY 0.872340 (-975 900);
DISPLAY INVISIBLE (-975 900);
FORCEPROP 1 LAST PATH I34
J 2
(-648 1025);
DISPLAY 0.872340 (-648 1025);
PAINT GREEN (-648 1025);
DISPLAY INVISIBLE (-648 1025);
FORCEADD TAP..1
R 2
(-650 1075);
FORCEPROP 3 LASTPIN (-600 1075) SIG_NAME M_H_CPU1_SB_DQ<16>
J 0
(-590 1085);
DISPLAY 0.659574 (-590 1085);
PAINT MONO (-590 1085);
DISPLAY INVISIBLE (-590 1085);
FORCEPROP 1 LASTPIN (-600 1075) BN 16
J 2
(-588 1083);
DISPLAY 0.680851 (-588 1083);
PAINT GREEN (-588 1083);
FORCEPROP 2 LAST CDS_LIB standard
J 0
(-650 1075);
DISPLAY INVISIBLE (-650 1075);
FORCEPROP 1 LAST BODY_TYPE PLUMBING
J 2
(-650 1125);
DISPLAY 0.872340 (-650 1125);
PAINT GREEN (-650 1125);
DISPLAY INVISIBLE (-650 1125);
FORCEPROP 1 LAST HDL_TAP TRUE
J 2
(-975 950);
DISPLAY 0.872340 (-975 950);
DISPLAY INVISIBLE (-975 950);
FORCEPROP 1 LAST PATH I35
J 2
(-648 1075);
DISPLAY 0.872340 (-648 1075);
PAINT GREEN (-648 1075);
DISPLAY INVISIBLE (-648 1075);
FORCEADD TAP..1
R 2
(-650 1175);
FORCEPROP 3 LASTPIN (-600 1175) SIG_NAME M_H_CPU1_SB_DQ<18>
J 0
(-590 1185);
DISPLAY 0.659574 (-590 1185);
PAINT MONO (-590 1185);
DISPLAY INVISIBLE (-590 1185);
FORCEPROP 1 LASTPIN (-600 1175) BN 18
J 2
(-588 1183);
DISPLAY 0.680851 (-588 1183);
PAINT GREEN (-588 1183);
FORCEPROP 2 LAST CDS_LIB standard
J 0
(-650 1175);
DISPLAY INVISIBLE (-650 1175);
FORCEPROP 1 LAST BODY_TYPE PLUMBING
J 2
(-650 1225);
DISPLAY 0.872340 (-650 1225);
PAINT GREEN (-650 1225);
DISPLAY INVISIBLE (-650 1225);
FORCEPROP 1 LAST HDL_TAP TRUE
J 2
(-975 1050);
DISPLAY 0.872340 (-975 1050);
DISPLAY INVISIBLE (-975 1050);
FORCEPROP 1 LAST PATH I36
J 2
(-648 1175);
DISPLAY 0.872340 (-648 1175);
PAINT GREEN (-648 1175);
DISPLAY INVISIBLE (-648 1175);
FORCEADD TAP..1
R 2
(-650 1125);
FORCEPROP 3 LASTPIN (-600 1125) SIG_NAME M_H_CPU1_SB_DQ<17>
J 0
(-590 1135);
DISPLAY 0.659574 (-590 1135);
PAINT MONO (-590 1135);
DISPLAY INVISIBLE (-590 1135);
FORCEPROP 1 LASTPIN (-600 1125) BN 17
J 2
(-588 1133);
DISPLAY 0.680851 (-588 1133);
PAINT GREEN (-588 1133);
FORCEPROP 2 LAST CDS_LIB standard
J 0
(-650 1125);
DISPLAY INVISIBLE (-650 1125);
FORCEPROP 1 LAST BODY_TYPE PLUMBING
J 2
(-650 1175);
DISPLAY 0.872340 (-650 1175);
PAINT GREEN (-650 1175);
DISPLAY INVISIBLE (-650 1175);
FORCEPROP 1 LAST HDL_TAP TRUE
J 2
(-975 1000);
DISPLAY 0.872340 (-975 1000);
DISPLAY INVISIBLE (-975 1000);
FORCEPROP 1 LAST PATH I37
J 2
(-648 1125);
DISPLAY 0.872340 (-648 1125);
PAINT GREEN (-648 1125);
DISPLAY INVISIBLE (-648 1125);
FORCEADD TAP..1
R 2
(-650 1225);
FORCEPROP 3 LASTPIN (-600 1225) SIG_NAME M_H_CPU1_SB_DQ<19>
J 0
(-590 1235);
DISPLAY 0.659574 (-590 1235);
PAINT MONO (-590 1235);
DISPLAY INVISIBLE (-590 1235);
FORCEPROP 1 LASTPIN (-600 1225) BN 19
J 2
(-588 1233);
DISPLAY 0.680851 (-588 1233);
PAINT GREEN (-588 1233);
FORCEPROP 2 LAST CDS_LIB standard
J 0
(-650 1225);
DISPLAY INVISIBLE (-650 1225);
FORCEPROP 1 LAST BODY_TYPE PLUMBING
J 2
(-650 1275);
DISPLAY 0.872340 (-650 1275);
PAINT GREEN (-650 1275);
DISPLAY INVISIBLE (-650 1275);
FORCEPROP 1 LAST HDL_TAP TRUE
J 2
(-975 1100);
DISPLAY 0.872340 (-975 1100);
DISPLAY INVISIBLE (-975 1100);
FORCEPROP 1 LAST PATH I38
J 2
(-648 1225);
DISPLAY 0.872340 (-648 1225);
PAINT GREEN (-648 1225);
DISPLAY INVISIBLE (-648 1225);
FORCEADD TAP..1
R 2
(-650 1325);
FORCEPROP 3 LASTPIN (-600 1325) SIG_NAME M_H_CPU1_SB_DQ<21>
J 0
(-590 1335);
DISPLAY 0.659574 (-590 1335);
PAINT MONO (-590 1335);
DISPLAY INVISIBLE (-590 1335);
FORCEPROP 1 LASTPIN (-600 1325) BN 21
J 2
(-588 1333);
DISPLAY 0.680851 (-588 1333);
PAINT GREEN (-588 1333);
FORCEPROP 2 LAST CDS_LIB standard
J 0
(-650 1325);
DISPLAY INVISIBLE (-650 1325);
FORCEPROP 1 LAST BODY_TYPE PLUMBING
J 2
(-650 1375);
DISPLAY 0.872340 (-650 1375);
PAINT GREEN (-650 1375);
DISPLAY INVISIBLE (-650 1375);
FORCEPROP 1 LAST HDL_TAP TRUE
J 2
(-975 1200);
DISPLAY 0.872340 (-975 1200);
DISPLAY INVISIBLE (-975 1200);
FORCEPROP 1 LAST PATH I39
J 2
(-648 1325);
DISPLAY 0.872340 (-648 1325);
PAINT GREEN (-648 1325);
DISPLAY INVISIBLE (-648 1325);
FORCEADD OFFPAGE..3
R 2
(-1675 1850);
FORCEPROP 2 LAST $XR1 113 
J 0
(-2105 1850);
DISPLAY 0.638298 (-2105 1850);
PAINT MONO (-2105 1850);
FORCEPROP 2 LAST $XR0 112 
J 0
(-1985 1850);
DISPLAY 0.638298 (-1985 1850);
PAINT MONO (-1985 1850);
FORCEPROP 2 LAST CDS_LIB standard
J 0
(-1675 1850);
DISPLAY INVISIBLE (-1675 1850);
FORCEPROP 1 LAST OFFPAGE TRUE
J 2
(-2000 1725);
DISPLAY 0.872340 (-2000 1725);
DISPLAY INVISIBLE (-2000 1725);
FORCEPROP 1 LAST COMMENT_BODY TRUE
J 2
(-1625 1750);
DISPLAY 0.872340 (-1625 1750);
PAINT GREEN (-1625 1750);
DISPLAY INVISIBLE (-1625 1750);
FORCEPROP 2 LAST PATH I4
J 0
(-1625 1925);
DISPLAY 1.021277 (-1625 1925);
DISPLAY INVISIBLE (-1625 1925);
FORCEADD TAP..1
R 2
(-650 1275);
FORCEPROP 3 LASTPIN (-600 1275) SIG_NAME M_H_CPU1_SB_DQ<20>
J 0
(-590 1285);
DISPLAY 0.659574 (-590 1285);
PAINT MONO (-590 1285);
DISPLAY INVISIBLE (-590 1285);
FORCEPROP 1 LASTPIN (-600 1275) BN 20
J 2
(-588 1283);
DISPLAY 0.680851 (-588 1283);
PAINT GREEN (-588 1283);
FORCEPROP 2 LAST CDS_LIB standard
J 0
(-650 1275);
DISPLAY INVISIBLE (-650 1275);
FORCEPROP 1 LAST BODY_TYPE PLUMBING
J 2
(-650 1325);
DISPLAY 0.872340 (-650 1325);
PAINT GREEN (-650 1325);
DISPLAY INVISIBLE (-650 1325);
FORCEPROP 1 LAST HDL_TAP TRUE
J 2
(-975 1150);
DISPLAY 0.872340 (-975 1150);
DISPLAY INVISIBLE (-975 1150);
FORCEPROP 1 LAST PATH I40
J 2
(-648 1275);
DISPLAY 0.872340 (-648 1275);
PAINT GREEN (-648 1275);
DISPLAY INVISIBLE (-648 1275);
FORCEADD TAP..1
R 2
(-650 1375);
FORCEPROP 3 LASTPIN (-600 1375) SIG_NAME M_H_CPU1_SB_DQ<22>
J 0
(-590 1385);
DISPLAY 0.659574 (-590 1385);
PAINT MONO (-590 1385);
DISPLAY INVISIBLE (-590 1385);
FORCEPROP 1 LASTPIN (-600 1375) BN 22
J 2
(-588 1383);
DISPLAY 0.680851 (-588 1383);
PAINT GREEN (-588 1383);
FORCEPROP 2 LAST CDS_LIB standard
J 0
(-650 1375);
DISPLAY INVISIBLE (-650 1375);
FORCEPROP 1 LAST BODY_TYPE PLUMBING
J 2
(-650 1425);
DISPLAY 0.872340 (-650 1425);
PAINT GREEN (-650 1425);
DISPLAY INVISIBLE (-650 1425);
FORCEPROP 1 LAST HDL_TAP TRUE
J 2
(-975 1250);
DISPLAY 0.872340 (-975 1250);
DISPLAY INVISIBLE (-975 1250);
FORCEPROP 1 LAST PATH I41
J 2
(-648 1375);
DISPLAY 0.872340 (-648 1375);
PAINT GREEN (-648 1375);
DISPLAY INVISIBLE (-648 1375);
FORCEADD TAP..1
R 2
(-650 1425);
FORCEPROP 3 LASTPIN (-600 1425) SIG_NAME M_H_CPU1_SB_DQ<23>
J 0
(-590 1435);
DISPLAY 0.659574 (-590 1435);
PAINT MONO (-590 1435);
DISPLAY INVISIBLE (-590 1435);
FORCEPROP 1 LASTPIN (-600 1425) BN 23
J 2
(-588 1433);
DISPLAY 0.680851 (-588 1433);
PAINT GREEN (-588 1433);
FORCEPROP 2 LAST CDS_LIB standard
J 0
(-650 1425);
DISPLAY INVISIBLE (-650 1425);
FORCEPROP 1 LAST BODY_TYPE PLUMBING
J 2
(-650 1475);
DISPLAY 0.872340 (-650 1475);
PAINT GREEN (-650 1475);
DISPLAY INVISIBLE (-650 1475);
FORCEPROP 1 LAST HDL_TAP TRUE
J 2
(-975 1300);
DISPLAY 0.872340 (-975 1300);
DISPLAY INVISIBLE (-975 1300);
FORCEPROP 1 LAST PATH I42
J 2
(-648 1425);
DISPLAY 0.872340 (-648 1425);
PAINT GREEN (-648 1425);
DISPLAY INVISIBLE (-648 1425);
FORCEADD TAP..1
R 2
(-650 1475);
FORCEPROP 3 LASTPIN (-600 1475) SIG_NAME M_H_CPU1_SB_DQ<24>
J 0
(-590 1485);
DISPLAY 0.659574 (-590 1485);
PAINT MONO (-590 1485);
DISPLAY INVISIBLE (-590 1485);
FORCEPROP 1 LASTPIN (-600 1475) BN 24
J 2
(-588 1483);
DISPLAY 0.680851 (-588 1483);
PAINT GREEN (-588 1483);
FORCEPROP 2 LAST CDS_LIB standard
J 0
(-650 1475);
DISPLAY INVISIBLE (-650 1475);
FORCEPROP 1 LAST BODY_TYPE PLUMBING
J 2
(-650 1525);
DISPLAY 0.872340 (-650 1525);
PAINT GREEN (-650 1525);
DISPLAY INVISIBLE (-650 1525);
FORCEPROP 1 LAST HDL_TAP TRUE
J 2
(-975 1350);
DISPLAY 0.872340 (-975 1350);
DISPLAY INVISIBLE (-975 1350);
FORCEPROP 1 LAST PATH I43
J 2
(-648 1475);
DISPLAY 0.872340 (-648 1475);
PAINT GREEN (-648 1475);
DISPLAY INVISIBLE (-648 1475);
FORCEADD TAP..1
R 2
(-650 1525);
FORCEPROP 3 LASTPIN (-600 1525) SIG_NAME M_H_CPU1_SB_DQ<25>
J 0
(-590 1535);
DISPLAY 0.659574 (-590 1535);
PAINT MONO (-590 1535);
DISPLAY INVISIBLE (-590 1535);
FORCEPROP 1 LASTPIN (-600 1525) BN 25
J 2
(-588 1533);
DISPLAY 0.680851 (-588 1533);
PAINT GREEN (-588 1533);
FORCEPROP 2 LAST CDS_LIB standard
J 0
(-650 1525);
DISPLAY INVISIBLE (-650 1525);
FORCEPROP 1 LAST BODY_TYPE PLUMBING
J 2
(-650 1575);
DISPLAY 0.872340 (-650 1575);
PAINT GREEN (-650 1575);
DISPLAY INVISIBLE (-650 1575);
FORCEPROP 1 LAST HDL_TAP TRUE
J 2
(-975 1400);
DISPLAY 0.872340 (-975 1400);
DISPLAY INVISIBLE (-975 1400);
FORCEPROP 1 LAST PATH I44
J 2
(-648 1525);
DISPLAY 0.872340 (-648 1525);
PAINT GREEN (-648 1525);
DISPLAY INVISIBLE (-648 1525);
FORCEADD TAP..1
R 2
(-650 1575);
FORCEPROP 3 LASTPIN (-600 1575) SIG_NAME M_H_CPU1_SB_DQ<26>
J 0
(-590 1585);
DISPLAY 0.659574 (-590 1585);
PAINT MONO (-590 1585);
DISPLAY INVISIBLE (-590 1585);
FORCEPROP 1 LASTPIN (-600 1575) BN 26
J 2
(-588 1583);
DISPLAY 0.680851 (-588 1583);
PAINT GREEN (-588 1583);
FORCEPROP 2 LAST CDS_LIB standard
J 0
(-650 1575);
DISPLAY INVISIBLE (-650 1575);
FORCEPROP 1 LAST BODY_TYPE PLUMBING
J 2
(-650 1625);
DISPLAY 0.872340 (-650 1625);
PAINT GREEN (-650 1625);
DISPLAY INVISIBLE (-650 1625);
FORCEPROP 1 LAST HDL_TAP TRUE
J 2
(-975 1450);
DISPLAY 0.872340 (-975 1450);
DISPLAY INVISIBLE (-975 1450);
FORCEPROP 1 LAST PATH I45
J 2
(-648 1575);
DISPLAY 0.872340 (-648 1575);
PAINT GREEN (-648 1575);
DISPLAY INVISIBLE (-648 1575);
FORCEADD TAP..1
R 2
(-650 1625);
FORCEPROP 3 LASTPIN (-600 1625) SIG_NAME M_H_CPU1_SB_DQ<27>
J 0
(-590 1635);
DISPLAY 0.659574 (-590 1635);
PAINT MONO (-590 1635);
DISPLAY INVISIBLE (-590 1635);
FORCEPROP 1 LASTPIN (-600 1625) BN 27
J 2
(-588 1633);
DISPLAY 0.680851 (-588 1633);
PAINT GREEN (-588 1633);
FORCEPROP 2 LAST CDS_LIB standard
J 0
(-650 1625);
DISPLAY INVISIBLE (-650 1625);
FORCEPROP 1 LAST BODY_TYPE PLUMBING
J 2
(-650 1675);
DISPLAY 0.872340 (-650 1675);
PAINT GREEN (-650 1675);
DISPLAY INVISIBLE (-650 1675);
FORCEPROP 1 LAST HDL_TAP TRUE
J 2
(-975 1500);
DISPLAY 0.872340 (-975 1500);
DISPLAY INVISIBLE (-975 1500);
FORCEPROP 1 LAST PATH I46
J 2
(-648 1625);
DISPLAY 0.872340 (-648 1625);
PAINT GREEN (-648 1625);
DISPLAY INVISIBLE (-648 1625);
FORCEADD TAP..1
R 2
(-650 1675);
FORCEPROP 3 LASTPIN (-600 1675) SIG_NAME M_H_CPU1_SB_DQ<28>
J 0
(-590 1685);
DISPLAY 0.659574 (-590 1685);
PAINT MONO (-590 1685);
DISPLAY INVISIBLE (-590 1685);
FORCEPROP 1 LASTPIN (-600 1675) BN 28
J 2
(-588 1683);
DISPLAY 0.680851 (-588 1683);
PAINT GREEN (-588 1683);
FORCEPROP 2 LAST CDS_LIB standard
J 0
(-650 1675);
DISPLAY INVISIBLE (-650 1675);
FORCEPROP 1 LAST BODY_TYPE PLUMBING
J 2
(-650 1725);
DISPLAY 0.872340 (-650 1725);
PAINT GREEN (-650 1725);
DISPLAY INVISIBLE (-650 1725);
FORCEPROP 1 LAST HDL_TAP TRUE
J 2
(-975 1550);
DISPLAY 0.872340 (-975 1550);
DISPLAY INVISIBLE (-975 1550);
FORCEPROP 1 LAST PATH I47
J 2
(-648 1675);
DISPLAY 0.872340 (-648 1675);
PAINT GREEN (-648 1675);
DISPLAY INVISIBLE (-648 1675);
FORCEADD TAP..1
R 2
(-650 1725);
FORCEPROP 3 LASTPIN (-600 1725) SIG_NAME M_H_CPU1_SB_DQ<29>
J 0
(-590 1735);
DISPLAY 0.659574 (-590 1735);
PAINT MONO (-590 1735);
DISPLAY INVISIBLE (-590 1735);
FORCEPROP 1 LASTPIN (-600 1725) BN 29
J 2
(-588 1733);
DISPLAY 0.680851 (-588 1733);
PAINT GREEN (-588 1733);
FORCEPROP 2 LAST CDS_LIB standard
J 0
(-650 1725);
DISPLAY INVISIBLE (-650 1725);
FORCEPROP 1 LAST BODY_TYPE PLUMBING
J 2
(-650 1775);
DISPLAY 0.872340 (-650 1775);
PAINT GREEN (-650 1775);
DISPLAY INVISIBLE (-650 1775);
FORCEPROP 1 LAST HDL_TAP TRUE
J 2
(-975 1600);
DISPLAY 0.872340 (-975 1600);
DISPLAY INVISIBLE (-975 1600);
FORCEPROP 1 LAST PATH I48
J 2
(-648 1725);
DISPLAY 0.872340 (-648 1725);
PAINT GREEN (-648 1725);
DISPLAY INVISIBLE (-648 1725);
FORCEADD TAP..1
R 2
(-650 1825);
FORCEPROP 3 LASTPIN (-600 1825) SIG_NAME M_H_CPU1_SB_DQ<31>
J 0
(-590 1835);
DISPLAY 0.659574 (-590 1835);
PAINT MONO (-590 1835);
DISPLAY INVISIBLE (-590 1835);
FORCEPROP 1 LASTPIN (-600 1825) BN 31
J 2
(-588 1833);
DISPLAY 0.680851 (-588 1833);
PAINT GREEN (-588 1833);
FORCEPROP 2 LAST CDS_LIB standard
J 0
(-650 1825);
DISPLAY INVISIBLE (-650 1825);
FORCEPROP 1 LAST BODY_TYPE PLUMBING
J 2
(-650 1875);
DISPLAY 0.872340 (-650 1875);
PAINT GREEN (-650 1875);
DISPLAY INVISIBLE (-650 1875);
FORCEPROP 1 LAST HDL_TAP TRUE
J 2
(-975 1700);
DISPLAY 0.872340 (-975 1700);
DISPLAY INVISIBLE (-975 1700);
FORCEPROP 1 LAST PATH I49
J 2
(-648 1825);
DISPLAY 0.872340 (-648 1825);
PAINT GREEN (-648 1825);
DISPLAY INVISIBLE (-648 1825);
FORCEADD OFFPAGE..3
R 2
(-1675 2250);
FORCEPROP 2 LAST $XR1 113 
J 0
(-2105 2250);
DISPLAY 0.638298 (-2105 2250);
PAINT MONO (-2105 2250);
FORCEPROP 2 LAST $XR0 112 
J 0
(-1985 2250);
DISPLAY 0.638298 (-1985 2250);
PAINT MONO (-1985 2250);
FORCEPROP 2 LAST CDS_LIB standard
J 0
(-1675 2250);
DISPLAY INVISIBLE (-1675 2250);
FORCEPROP 1 LAST OFFPAGE TRUE
J 2
(-2000 2125);
DISPLAY 0.872340 (-2000 2125);
DISPLAY INVISIBLE (-2000 2125);
FORCEPROP 1 LAST COMMENT_BODY TRUE
J 2
(-1625 2150);
DISPLAY 0.872340 (-1625 2150);
PAINT GREEN (-1625 2150);
DISPLAY INVISIBLE (-1625 2150);
FORCEPROP 2 LAST PATH I5
J 0
(-1625 2325);
DISPLAY 1.021277 (-1625 2325);
DISPLAY INVISIBLE (-1625 2325);
FORCEADD TAP..1
R 2
(-650 1775);
FORCEPROP 3 LASTPIN (-600 1775) SIG_NAME M_H_CPU1_SB_DQ<30>
J 0
(-590 1785);
DISPLAY 0.659574 (-590 1785);
PAINT MONO (-590 1785);
DISPLAY INVISIBLE (-590 1785);
FORCEPROP 1 LASTPIN (-600 1775) BN 30
J 2
(-588 1783);
DISPLAY 0.680851 (-588 1783);
PAINT GREEN (-588 1783);
FORCEPROP 2 LAST CDS_LIB standard
J 0
(-650 1775);
DISPLAY INVISIBLE (-650 1775);
FORCEPROP 1 LAST BODY_TYPE PLUMBING
J 2
(-650 1825);
DISPLAY 0.872340 (-650 1825);
PAINT GREEN (-650 1825);
DISPLAY INVISIBLE (-650 1825);
FORCEPROP 1 LAST HDL_TAP TRUE
J 2
(-975 1650);
DISPLAY 0.872340 (-975 1650);
DISPLAY INVISIBLE (-975 1650);
FORCEPROP 1 LAST PATH I50
J 2
(-648 1775);
DISPLAY 0.872340 (-648 1775);
PAINT GREEN (-648 1775);
DISPLAY INVISIBLE (-648 1775);
FORCEADD TAP..1
R 2
(-650 1875);
FORCEPROP 3 LASTPIN (-600 1875) SIG_NAME M_H_CPU1_SA_CB<0>
J 0
(-590 1885);
DISPLAY 0.659574 (-590 1885);
PAINT MONO (-590 1885);
DISPLAY INVISIBLE (-590 1885);
FORCEPROP 1 LASTPIN (-600 1875) BN 0
J 2
(-588 1883);
DISPLAY 0.680851 (-588 1883);
PAINT GREEN (-588 1883);
FORCEPROP 2 LAST CDS_LIB standard
J 0
(-650 1875);
DISPLAY INVISIBLE (-650 1875);
FORCEPROP 1 LAST BODY_TYPE PLUMBING
J 2
(-650 1925);
DISPLAY 0.872340 (-650 1925);
PAINT GREEN (-650 1925);
DISPLAY INVISIBLE (-650 1925);
FORCEPROP 1 LAST HDL_TAP TRUE
J 2
(-975 1750);
DISPLAY 0.872340 (-975 1750);
DISPLAY INVISIBLE (-975 1750);
FORCEPROP 1 LAST PATH I51
J 2
(-648 1875);
DISPLAY 0.872340 (-648 1875);
PAINT GREEN (-648 1875);
DISPLAY INVISIBLE (-648 1875);
FORCEADD TAP..1
R 2
(-650 1975);
FORCEPROP 3 LASTPIN (-600 1975) SIG_NAME M_H_CPU1_SA_CB<2>
J 0
(-590 1985);
DISPLAY 0.659574 (-590 1985);
PAINT MONO (-590 1985);
DISPLAY INVISIBLE (-590 1985);
FORCEPROP 1 LASTPIN (-600 1975) BN 2
J 2
(-588 1983);
DISPLAY 0.680851 (-588 1983);
PAINT GREEN (-588 1983);
FORCEPROP 2 LAST CDS_LIB standard
J 0
(-650 1975);
DISPLAY INVISIBLE (-650 1975);
FORCEPROP 1 LAST BODY_TYPE PLUMBING
J 2
(-650 2025);
DISPLAY 0.872340 (-650 2025);
PAINT GREEN (-650 2025);
DISPLAY INVISIBLE (-650 2025);
FORCEPROP 1 LAST HDL_TAP TRUE
J 2
(-975 1850);
DISPLAY 0.872340 (-975 1850);
DISPLAY INVISIBLE (-975 1850);
FORCEPROP 1 LAST PATH I52
J 2
(-648 1975);
DISPLAY 0.872340 (-648 1975);
PAINT GREEN (-648 1975);
DISPLAY INVISIBLE (-648 1975);
FORCEADD TAP..1
R 2
(-650 1925);
FORCEPROP 3 LASTPIN (-600 1925) SIG_NAME M_H_CPU1_SA_CB<1>
J 0
(-590 1935);
DISPLAY 0.659574 (-590 1935);
PAINT MONO (-590 1935);
DISPLAY INVISIBLE (-590 1935);
FORCEPROP 1 LASTPIN (-600 1925) BN 1
J 2
(-588 1933);
DISPLAY 0.680851 (-588 1933);
PAINT GREEN (-588 1933);
FORCEPROP 2 LAST CDS_LIB standard
J 0
(-650 1925);
DISPLAY INVISIBLE (-650 1925);
FORCEPROP 1 LAST BODY_TYPE PLUMBING
J 2
(-650 1975);
DISPLAY 0.872340 (-650 1975);
PAINT GREEN (-650 1975);
DISPLAY INVISIBLE (-650 1975);
FORCEPROP 1 LAST HDL_TAP TRUE
J 2
(-975 1800);
DISPLAY 0.872340 (-975 1800);
DISPLAY INVISIBLE (-975 1800);
FORCEPROP 1 LAST PATH I53
J 2
(-648 1925);
DISPLAY 0.872340 (-648 1925);
PAINT GREEN (-648 1925);
DISPLAY INVISIBLE (-648 1925);
FORCEADD TAP..1
R 2
(-650 2075);
FORCEPROP 3 LASTPIN (-600 2075) SIG_NAME M_H_CPU1_SA_CB<4>
J 0
(-590 2085);
DISPLAY 0.659574 (-590 2085);
PAINT MONO (-590 2085);
DISPLAY INVISIBLE (-590 2085);
FORCEPROP 1 LASTPIN (-600 2075) BN 4
J 2
(-588 2083);
DISPLAY 0.680851 (-588 2083);
PAINT GREEN (-588 2083);
FORCEPROP 2 LAST CDS_LIB standard
J 0
(-650 2075);
DISPLAY INVISIBLE (-650 2075);
FORCEPROP 1 LAST BODY_TYPE PLUMBING
J 2
(-650 2125);
DISPLAY 0.872340 (-650 2125);
PAINT GREEN (-650 2125);
DISPLAY INVISIBLE (-650 2125);
FORCEPROP 1 LAST HDL_TAP TRUE
J 2
(-975 1950);
DISPLAY 0.872340 (-975 1950);
DISPLAY INVISIBLE (-975 1950);
FORCEPROP 1 LAST PATH I54
J 2
(-648 2075);
DISPLAY 0.872340 (-648 2075);
PAINT GREEN (-648 2075);
DISPLAY INVISIBLE (-648 2075);
FORCEADD TAP..1
R 2
(-650 2025);
FORCEPROP 3 LASTPIN (-600 2025) SIG_NAME M_H_CPU1_SA_CB<3>
J 0
(-590 2035);
DISPLAY 0.659574 (-590 2035);
PAINT MONO (-590 2035);
DISPLAY INVISIBLE (-590 2035);
FORCEPROP 1 LASTPIN (-600 2025) BN 3
J 2
(-588 2033);
DISPLAY 0.680851 (-588 2033);
PAINT GREEN (-588 2033);
FORCEPROP 2 LAST CDS_LIB standard
J 0
(-650 2025);
DISPLAY INVISIBLE (-650 2025);
FORCEPROP 1 LAST BODY_TYPE PLUMBING
J 2
(-650 2075);
DISPLAY 0.872340 (-650 2075);
PAINT GREEN (-650 2075);
DISPLAY INVISIBLE (-650 2075);
FORCEPROP 1 LAST HDL_TAP TRUE
J 2
(-975 1900);
DISPLAY 0.872340 (-975 1900);
DISPLAY INVISIBLE (-975 1900);
FORCEPROP 1 LAST PATH I55
J 2
(-648 2025);
DISPLAY 0.872340 (-648 2025);
PAINT GREEN (-648 2025);
DISPLAY INVISIBLE (-648 2025);
FORCEADD TAP..1
R 2
(-650 2125);
FORCEPROP 3 LASTPIN (-600 2125) SIG_NAME M_H_CPU1_SA_CB<5>
J 0
(-590 2135);
DISPLAY 0.659574 (-590 2135);
PAINT MONO (-590 2135);
DISPLAY INVISIBLE (-590 2135);
FORCEPROP 1 LASTPIN (-600 2125) BN 5
J 2
(-588 2133);
DISPLAY 0.680851 (-588 2133);
PAINT GREEN (-588 2133);
FORCEPROP 2 LAST CDS_LIB standard
J 0
(-650 2125);
DISPLAY INVISIBLE (-650 2125);
FORCEPROP 1 LAST BODY_TYPE PLUMBING
J 2
(-650 2175);
DISPLAY 0.872340 (-650 2175);
PAINT GREEN (-650 2175);
DISPLAY INVISIBLE (-650 2175);
FORCEPROP 1 LAST HDL_TAP TRUE
J 2
(-975 2000);
DISPLAY 0.872340 (-975 2000);
DISPLAY INVISIBLE (-975 2000);
FORCEPROP 1 LAST PATH I56
J 2
(-648 2125);
DISPLAY 0.872340 (-648 2125);
PAINT GREEN (-648 2125);
DISPLAY INVISIBLE (-648 2125);
FORCEADD TAP..1
R 2
(-650 2225);
FORCEPROP 3 LASTPIN (-600 2225) SIG_NAME M_H_CPU1_SA_CB<7>
J 0
(-590 2235);
DISPLAY 0.659574 (-590 2235);
PAINT MONO (-590 2235);
DISPLAY INVISIBLE (-590 2235);
FORCEPROP 1 LASTPIN (-600 2225) BN 7
J 2
(-588 2233);
DISPLAY 0.680851 (-588 2233);
PAINT GREEN (-588 2233);
FORCEPROP 2 LAST CDS_LIB standard
J 0
(-650 2225);
DISPLAY INVISIBLE (-650 2225);
FORCEPROP 1 LAST BODY_TYPE PLUMBING
J 2
(-650 2275);
DISPLAY 0.872340 (-650 2275);
PAINT GREEN (-650 2275);
DISPLAY INVISIBLE (-650 2275);
FORCEPROP 1 LAST HDL_TAP TRUE
J 2
(-975 2100);
DISPLAY 0.872340 (-975 2100);
DISPLAY INVISIBLE (-975 2100);
FORCEPROP 1 LAST PATH I57
J 2
(-648 2225);
DISPLAY 0.872340 (-648 2225);
PAINT GREEN (-648 2225);
DISPLAY INVISIBLE (-648 2225);
FORCEADD TAP..1
R 2
(-650 2175);
FORCEPROP 3 LASTPIN (-600 2175) SIG_NAME M_H_CPU1_SA_CB<6>
J 0
(-590 2185);
DISPLAY 0.659574 (-590 2185);
PAINT MONO (-590 2185);
DISPLAY INVISIBLE (-590 2185);
FORCEPROP 1 LASTPIN (-600 2175) BN 6
J 2
(-588 2183);
DISPLAY 0.680851 (-588 2183);
PAINT GREEN (-588 2183);
FORCEPROP 2 LAST CDS_LIB standard
J 0
(-650 2175);
DISPLAY INVISIBLE (-650 2175);
FORCEPROP 1 LAST BODY_TYPE PLUMBING
J 2
(-650 2225);
DISPLAY 0.872340 (-650 2225);
PAINT GREEN (-650 2225);
DISPLAY INVISIBLE (-650 2225);
FORCEPROP 1 LAST HDL_TAP TRUE
J 2
(-975 2050);
DISPLAY 0.872340 (-975 2050);
DISPLAY INVISIBLE (-975 2050);
FORCEPROP 1 LAST PATH I58
J 2
(-648 2175);
DISPLAY 0.872340 (-648 2175);
PAINT GREEN (-648 2175);
DISPLAY INVISIBLE (-648 2175);
FORCEADD TAP..1
R 2
(-650 2325);
FORCEPROP 3 LASTPIN (-600 2325) SIG_NAME M_H_CPU1_SA_DQ<1>
J 0
(-590 2335);
DISPLAY 0.659574 (-590 2335);
PAINT MONO (-590 2335);
DISPLAY INVISIBLE (-590 2335);
FORCEPROP 1 LASTPIN (-600 2325) BN 1
J 2
(-588 2333);
DISPLAY 0.680851 (-588 2333);
PAINT GREEN (-588 2333);
FORCEPROP 2 LAST CDS_LIB standard
J 0
(-650 2325);
DISPLAY INVISIBLE (-650 2325);
FORCEPROP 1 LAST BODY_TYPE PLUMBING
J 2
(-650 2375);
DISPLAY 0.872340 (-650 2375);
PAINT GREEN (-650 2375);
DISPLAY INVISIBLE (-650 2375);
FORCEPROP 1 LAST HDL_TAP TRUE
J 2
(-975 2200);
DISPLAY 0.872340 (-975 2200);
DISPLAY INVISIBLE (-975 2200);
FORCEPROP 1 LAST PATH I59
J 2
(-648 2325);
DISPLAY 0.872340 (-648 2325);
PAINT GREEN (-648 2325);
DISPLAY INVISIBLE (-648 2325);
FORCEADD TAP..1
R 2
(-650 -325);
FORCEPROP 3 LASTPIN (-600 -325) SIG_NAME M_H_CPU1_CLK_DN<1>
J 0
(-590 -315);
DISPLAY 0.659574 (-590 -315);
PAINT MONO (-590 -315);
DISPLAY INVISIBLE (-590 -315);
FORCEPROP 1 LASTPIN (-600 -325) BN 1
J 2
(-588 -317);
DISPLAY 0.680851 (-588 -317);
PAINT GREEN (-588 -317);
FORCEPROP 2 LAST CDS_LIB standard
J 0
(-650 -325);
DISPLAY INVISIBLE (-650 -325);
FORCEPROP 1 LAST BODY_TYPE PLUMBING
J 2
(-650 -275);
DISPLAY 0.872340 (-650 -275);
PAINT GREEN (-650 -275);
DISPLAY INVISIBLE (-650 -275);
FORCEPROP 1 LAST HDL_TAP TRUE
J 2
(-975 -450);
DISPLAY 0.872340 (-975 -450);
DISPLAY INVISIBLE (-975 -450);
FORCEPROP 1 LAST PATH I6
J 2
(-648 -325);
DISPLAY 0.872340 (-648 -325);
PAINT GREEN (-648 -325);
DISPLAY INVISIBLE (-648 -325);
FORCEADD TAP..1
R 2
(-650 2275);
FORCEPROP 3 LASTPIN (-600 2275) SIG_NAME M_H_CPU1_SA_DQ<0>
J 0
(-590 2285);
DISPLAY 0.659574 (-590 2285);
PAINT MONO (-590 2285);
DISPLAY INVISIBLE (-590 2285);
FORCEPROP 1 LASTPIN (-600 2275) BN 0
J 2
(-588 2283);
DISPLAY 0.680851 (-588 2283);
PAINT GREEN (-588 2283);
FORCEPROP 2 LAST CDS_LIB standard
J 0
(-650 2275);
DISPLAY INVISIBLE (-650 2275);
FORCEPROP 1 LAST BODY_TYPE PLUMBING
J 2
(-650 2325);
DISPLAY 0.872340 (-650 2325);
PAINT GREEN (-650 2325);
DISPLAY INVISIBLE (-650 2325);
FORCEPROP 1 LAST HDL_TAP TRUE
J 2
(-975 2150);
DISPLAY 0.872340 (-975 2150);
DISPLAY INVISIBLE (-975 2150);
FORCEPROP 1 LAST PATH I60
J 2
(-648 2275);
DISPLAY 0.872340 (-648 2275);
PAINT GREEN (-648 2275);
DISPLAY INVISIBLE (-648 2275);
FORCEADD TAP..1
R 2
(-650 2375);
FORCEPROP 3 LASTPIN (-600 2375) SIG_NAME M_H_CPU1_SA_DQ<2>
J 0
(-590 2385);
DISPLAY 0.659574 (-590 2385);
PAINT MONO (-590 2385);
DISPLAY INVISIBLE (-590 2385);
FORCEPROP 1 LASTPIN (-600 2375) BN 2
J 2
(-588 2383);
DISPLAY 0.680851 (-588 2383);
PAINT GREEN (-588 2383);
FORCEPROP 2 LAST CDS_LIB standard
J 0
(-650 2375);
DISPLAY INVISIBLE (-650 2375);
FORCEPROP 1 LAST BODY_TYPE PLUMBING
J 2
(-650 2425);
DISPLAY 0.872340 (-650 2425);
PAINT GREEN (-650 2425);
DISPLAY INVISIBLE (-650 2425);
FORCEPROP 1 LAST HDL_TAP TRUE
J 2
(-975 2250);
DISPLAY 0.872340 (-975 2250);
DISPLAY INVISIBLE (-975 2250);
FORCEPROP 1 LAST PATH I61
J 2
(-648 2375);
DISPLAY 0.872340 (-648 2375);
PAINT GREEN (-648 2375);
DISPLAY INVISIBLE (-648 2375);
FORCEADD TAP..1
R 2
(-650 2475);
FORCEPROP 3 LASTPIN (-600 2475) SIG_NAME M_H_CPU1_SA_DQ<4>
J 0
(-590 2485);
DISPLAY 0.659574 (-590 2485);
PAINT MONO (-590 2485);
DISPLAY INVISIBLE (-590 2485);
FORCEPROP 1 LASTPIN (-600 2475) BN 4
J 2
(-588 2483);
DISPLAY 0.680851 (-588 2483);
PAINT GREEN (-588 2483);
FORCEPROP 2 LAST CDS_LIB standard
J 0
(-650 2475);
DISPLAY INVISIBLE (-650 2475);
FORCEPROP 1 LAST BODY_TYPE PLUMBING
J 2
(-650 2525);
DISPLAY 0.872340 (-650 2525);
PAINT GREEN (-650 2525);
DISPLAY INVISIBLE (-650 2525);
FORCEPROP 1 LAST HDL_TAP TRUE
J 2
(-975 2350);
DISPLAY 0.872340 (-975 2350);
DISPLAY INVISIBLE (-975 2350);
FORCEPROP 1 LAST PATH I62
J 2
(-648 2475);
DISPLAY 0.872340 (-648 2475);
PAINT GREEN (-648 2475);
DISPLAY INVISIBLE (-648 2475);
FORCEADD TAP..1
R 2
(-650 2425);
FORCEPROP 3 LASTPIN (-600 2425) SIG_NAME M_H_CPU1_SA_DQ<3>
J 0
(-590 2435);
DISPLAY 0.659574 (-590 2435);
PAINT MONO (-590 2435);
DISPLAY INVISIBLE (-590 2435);
FORCEPROP 1 LASTPIN (-600 2425) BN 3
J 2
(-588 2433);
DISPLAY 0.680851 (-588 2433);
PAINT GREEN (-588 2433);
FORCEPROP 2 LAST CDS_LIB standard
J 0
(-650 2425);
DISPLAY INVISIBLE (-650 2425);
FORCEPROP 1 LAST BODY_TYPE PLUMBING
J 2
(-650 2475);
DISPLAY 0.872340 (-650 2475);
PAINT GREEN (-650 2475);
DISPLAY INVISIBLE (-650 2475);
FORCEPROP 1 LAST HDL_TAP TRUE
J 2
(-975 2300);
DISPLAY 0.872340 (-975 2300);
DISPLAY INVISIBLE (-975 2300);
FORCEPROP 1 LAST PATH I63
J 2
(-648 2425);
DISPLAY 0.872340 (-648 2425);
PAINT GREEN (-648 2425);
DISPLAY INVISIBLE (-648 2425);
FORCEADD TAP..1
R 2
(-650 2525);
FORCEPROP 3 LASTPIN (-600 2525) SIG_NAME M_H_CPU1_SA_DQ<5>
J 0
(-590 2535);
DISPLAY 0.659574 (-590 2535);
PAINT MONO (-590 2535);
DISPLAY INVISIBLE (-590 2535);
FORCEPROP 1 LASTPIN (-600 2525) BN 5
J 2
(-588 2533);
DISPLAY 0.680851 (-588 2533);
PAINT GREEN (-588 2533);
FORCEPROP 2 LAST CDS_LIB standard
J 0
(-650 2525);
DISPLAY INVISIBLE (-650 2525);
FORCEPROP 1 LAST BODY_TYPE PLUMBING
J 2
(-650 2575);
DISPLAY 0.872340 (-650 2575);
PAINT GREEN (-650 2575);
DISPLAY INVISIBLE (-650 2575);
FORCEPROP 1 LAST HDL_TAP TRUE
J 2
(-975 2400);
DISPLAY 0.872340 (-975 2400);
DISPLAY INVISIBLE (-975 2400);
FORCEPROP 1 LAST PATH I64
J 2
(-648 2525);
DISPLAY 0.872340 (-648 2525);
PAINT GREEN (-648 2525);
DISPLAY INVISIBLE (-648 2525);
FORCEADD TAP..1
R 2
(-650 2625);
FORCEPROP 3 LASTPIN (-600 2625) SIG_NAME M_H_CPU1_SA_DQ<7>
J 0
(-590 2635);
DISPLAY 0.659574 (-590 2635);
PAINT MONO (-590 2635);
DISPLAY INVISIBLE (-590 2635);
FORCEPROP 1 LASTPIN (-600 2625) BN 7
J 2
(-588 2633);
DISPLAY 0.680851 (-588 2633);
PAINT GREEN (-588 2633);
FORCEPROP 2 LAST CDS_LIB standard
J 0
(-650 2625);
DISPLAY INVISIBLE (-650 2625);
FORCEPROP 1 LAST BODY_TYPE PLUMBING
J 2
(-650 2675);
DISPLAY 0.872340 (-650 2675);
PAINT GREEN (-650 2675);
DISPLAY INVISIBLE (-650 2675);
FORCEPROP 1 LAST HDL_TAP TRUE
J 2
(-975 2500);
DISPLAY 0.872340 (-975 2500);
DISPLAY INVISIBLE (-975 2500);
FORCEPROP 1 LAST PATH I65
J 2
(-648 2625);
DISPLAY 0.872340 (-648 2625);
PAINT GREEN (-648 2625);
DISPLAY INVISIBLE (-648 2625);
FORCEADD TAP..1
R 2
(-650 2575);
FORCEPROP 3 LASTPIN (-600 2575) SIG_NAME M_H_CPU1_SA_DQ<6>
J 0
(-590 2585);
DISPLAY 0.659574 (-590 2585);
PAINT MONO (-590 2585);
DISPLAY INVISIBLE (-590 2585);
FORCEPROP 1 LASTPIN (-600 2575) BN 6
J 2
(-588 2583);
DISPLAY 0.680851 (-588 2583);
PAINT GREEN (-588 2583);
FORCEPROP 2 LAST CDS_LIB standard
J 0
(-650 2575);
DISPLAY INVISIBLE (-650 2575);
FORCEPROP 1 LAST BODY_TYPE PLUMBING
J 2
(-650 2625);
DISPLAY 0.872340 (-650 2625);
PAINT GREEN (-650 2625);
DISPLAY INVISIBLE (-650 2625);
FORCEPROP 1 LAST HDL_TAP TRUE
J 2
(-975 2450);
DISPLAY 0.872340 (-975 2450);
DISPLAY INVISIBLE (-975 2450);
FORCEPROP 1 LAST PATH I66
J 2
(-648 2575);
DISPLAY 0.872340 (-648 2575);
PAINT GREEN (-648 2575);
DISPLAY INVISIBLE (-648 2575);
FORCEADD TAP..1
R 2
(-650 2725);
FORCEPROP 3 LASTPIN (-600 2725) SIG_NAME M_H_CPU1_SA_DQ<9>
J 0
(-590 2735);
DISPLAY 0.659574 (-590 2735);
PAINT MONO (-590 2735);
DISPLAY INVISIBLE (-590 2735);
FORCEPROP 1 LASTPIN (-600 2725) BN 9
J 2
(-588 2733);
DISPLAY 0.680851 (-588 2733);
PAINT GREEN (-588 2733);
FORCEPROP 2 LAST CDS_LIB standard
J 0
(-650 2725);
DISPLAY INVISIBLE (-650 2725);
FORCEPROP 1 LAST BODY_TYPE PLUMBING
J 2
(-650 2775);
DISPLAY 0.872340 (-650 2775);
PAINT GREEN (-650 2775);
DISPLAY INVISIBLE (-650 2775);
FORCEPROP 1 LAST HDL_TAP TRUE
J 2
(-975 2600);
DISPLAY 0.872340 (-975 2600);
DISPLAY INVISIBLE (-975 2600);
FORCEPROP 1 LAST PATH I67
J 2
(-648 2725);
DISPLAY 0.872340 (-648 2725);
PAINT GREEN (-648 2725);
DISPLAY INVISIBLE (-648 2725);
FORCEADD TAP..1
R 2
(-650 2675);
FORCEPROP 3 LASTPIN (-600 2675) SIG_NAME M_H_CPU1_SA_DQ<8>
J 0
(-590 2685);
DISPLAY 0.659574 (-590 2685);
PAINT MONO (-590 2685);
DISPLAY INVISIBLE (-590 2685);
FORCEPROP 1 LASTPIN (-600 2675) BN 8
J 2
(-588 2683);
DISPLAY 0.680851 (-588 2683);
PAINT GREEN (-588 2683);
FORCEPROP 2 LAST CDS_LIB standard
J 0
(-650 2675);
DISPLAY INVISIBLE (-650 2675);
FORCEPROP 1 LAST BODY_TYPE PLUMBING
J 2
(-650 2725);
DISPLAY 0.872340 (-650 2725);
PAINT GREEN (-650 2725);
DISPLAY INVISIBLE (-650 2725);
FORCEPROP 1 LAST HDL_TAP TRUE
J 2
(-975 2550);
DISPLAY 0.872340 (-975 2550);
DISPLAY INVISIBLE (-975 2550);
FORCEPROP 1 LAST PATH I68
J 2
(-648 2675);
DISPLAY 0.872340 (-648 2675);
PAINT GREEN (-648 2675);
DISPLAY INVISIBLE (-648 2675);
FORCEADD TAP..1
R 2
(-650 2775);
FORCEPROP 3 LASTPIN (-600 2775) SIG_NAME M_H_CPU1_SA_DQ<10>
J 0
(-590 2785);
DISPLAY 0.659574 (-590 2785);
PAINT MONO (-590 2785);
DISPLAY INVISIBLE (-590 2785);
FORCEPROP 1 LASTPIN (-600 2775) BN 10
J 2
(-588 2783);
DISPLAY 0.680851 (-588 2783);
PAINT GREEN (-588 2783);
FORCEPROP 2 LAST CDS_LIB standard
J 0
(-650 2775);
DISPLAY INVISIBLE (-650 2775);
FORCEPROP 1 LAST BODY_TYPE PLUMBING
J 2
(-650 2825);
DISPLAY 0.872340 (-650 2825);
PAINT GREEN (-650 2825);
DISPLAY INVISIBLE (-650 2825);
FORCEPROP 1 LAST HDL_TAP TRUE
J 2
(-975 2650);
DISPLAY 0.872340 (-975 2650);
DISPLAY INVISIBLE (-975 2650);
FORCEPROP 1 LAST PATH I69
J 2
(-648 2775);
DISPLAY 0.872340 (-648 2775);
PAINT GREEN (-648 2775);
DISPLAY INVISIBLE (-648 2775);
FORCEADD TAP..1
R 2
(-650 -375);
FORCEPROP 3 LASTPIN (-600 -375) SIG_NAME M_H_CPU1_CLK_DN<0>
J 0
(-590 -365);
DISPLAY 0.659574 (-590 -365);
PAINT MONO (-590 -365);
DISPLAY INVISIBLE (-590 -365);
FORCEPROP 1 LASTPIN (-600 -375) BN 0
J 2
(-588 -367);
DISPLAY 0.680851 (-588 -367);
PAINT GREEN (-588 -367);
FORCEPROP 2 LAST CDS_LIB standard
J 0
(-650 -375);
DISPLAY INVISIBLE (-650 -375);
FORCEPROP 1 LAST BODY_TYPE PLUMBING
J 2
(-650 -325);
DISPLAY 0.872340 (-650 -325);
PAINT GREEN (-650 -325);
DISPLAY INVISIBLE (-650 -325);
FORCEPROP 1 LAST HDL_TAP TRUE
J 2
(-975 -500);
DISPLAY 0.872340 (-975 -500);
DISPLAY INVISIBLE (-975 -500);
FORCEPROP 1 LAST PATH I7
J 2
(-648 -375);
DISPLAY 0.872340 (-648 -375);
PAINT GREEN (-648 -375);
DISPLAY INVISIBLE (-648 -375);
FORCEADD TAP..1
R 2
(-650 2825);
FORCEPROP 3 LASTPIN (-600 2825) SIG_NAME M_H_CPU1_SA_DQ<11>
J 0
(-590 2835);
DISPLAY 0.659574 (-590 2835);
PAINT MONO (-590 2835);
DISPLAY INVISIBLE (-590 2835);
FORCEPROP 1 LASTPIN (-600 2825) BN 11
J 2
(-588 2833);
DISPLAY 0.680851 (-588 2833);
PAINT GREEN (-588 2833);
FORCEPROP 2 LAST CDS_LIB standard
J 0
(-650 2825);
DISPLAY INVISIBLE (-650 2825);
FORCEPROP 1 LAST BODY_TYPE PLUMBING
J 2
(-650 2875);
DISPLAY 0.872340 (-650 2875);
PAINT GREEN (-650 2875);
DISPLAY INVISIBLE (-650 2875);
FORCEPROP 1 LAST HDL_TAP TRUE
J 2
(-975 2700);
DISPLAY 0.872340 (-975 2700);
DISPLAY INVISIBLE (-975 2700);
FORCEPROP 1 LAST PATH I70
J 2
(-648 2825);
DISPLAY 0.872340 (-648 2825);
PAINT GREEN (-648 2825);
DISPLAY INVISIBLE (-648 2825);
FORCEADD TAP..1
R 2
(-650 2875);
FORCEPROP 3 LASTPIN (-600 2875) SIG_NAME M_H_CPU1_SA_DQ<12>
J 0
(-590 2885);
DISPLAY 0.659574 (-590 2885);
PAINT MONO (-590 2885);
DISPLAY INVISIBLE (-590 2885);
FORCEPROP 1 LASTPIN (-600 2875) BN 12
J 2
(-588 2883);
DISPLAY 0.680851 (-588 2883);
PAINT GREEN (-588 2883);
FORCEPROP 2 LAST CDS_LIB standard
J 0
(-650 2875);
DISPLAY INVISIBLE (-650 2875);
FORCEPROP 1 LAST BODY_TYPE PLUMBING
J 2
(-650 2925);
DISPLAY 0.872340 (-650 2925);
PAINT GREEN (-650 2925);
DISPLAY INVISIBLE (-650 2925);
FORCEPROP 1 LAST HDL_TAP TRUE
J 2
(-975 2750);
DISPLAY 0.872340 (-975 2750);
DISPLAY INVISIBLE (-975 2750);
FORCEPROP 1 LAST PATH I71
J 2
(-648 2875);
DISPLAY 0.872340 (-648 2875);
PAINT GREEN (-648 2875);
DISPLAY INVISIBLE (-648 2875);
FORCEADD TAP..1
R 2
(-650 2975);
FORCEPROP 3 LASTPIN (-600 2975) SIG_NAME M_H_CPU1_SA_DQ<14>
J 0
(-590 2985);
DISPLAY 0.659574 (-590 2985);
PAINT MONO (-590 2985);
DISPLAY INVISIBLE (-590 2985);
FORCEPROP 1 LASTPIN (-600 2975) BN 14
J 2
(-588 2983);
DISPLAY 0.680851 (-588 2983);
PAINT GREEN (-588 2983);
FORCEPROP 2 LAST CDS_LIB standard
J 0
(-650 2975);
DISPLAY INVISIBLE (-650 2975);
FORCEPROP 1 LAST BODY_TYPE PLUMBING
J 2
(-650 3025);
DISPLAY 0.872340 (-650 3025);
PAINT GREEN (-650 3025);
DISPLAY INVISIBLE (-650 3025);
FORCEPROP 1 LAST HDL_TAP TRUE
J 2
(-975 2850);
DISPLAY 0.872340 (-975 2850);
DISPLAY INVISIBLE (-975 2850);
FORCEPROP 1 LAST PATH I72
J 2
(-648 2975);
DISPLAY 0.872340 (-648 2975);
PAINT GREEN (-648 2975);
DISPLAY INVISIBLE (-648 2975);
FORCEADD TAP..1
R 2
(-650 2925);
FORCEPROP 3 LASTPIN (-600 2925) SIG_NAME M_H_CPU1_SA_DQ<13>
J 0
(-590 2935);
DISPLAY 0.659574 (-590 2935);
PAINT MONO (-590 2935);
DISPLAY INVISIBLE (-590 2935);
FORCEPROP 1 LASTPIN (-600 2925) BN 13
J 2
(-588 2933);
DISPLAY 0.680851 (-588 2933);
PAINT GREEN (-588 2933);
FORCEPROP 2 LAST CDS_LIB standard
J 0
(-650 2925);
DISPLAY INVISIBLE (-650 2925);
FORCEPROP 1 LAST BODY_TYPE PLUMBING
J 2
(-650 2975);
DISPLAY 0.872340 (-650 2975);
PAINT GREEN (-650 2975);
DISPLAY INVISIBLE (-650 2975);
FORCEPROP 1 LAST HDL_TAP TRUE
J 2
(-975 2800);
DISPLAY 0.872340 (-975 2800);
DISPLAY INVISIBLE (-975 2800);
FORCEPROP 1 LAST PATH I73
J 2
(-648 2925);
DISPLAY 0.872340 (-648 2925);
PAINT GREEN (-648 2925);
DISPLAY INVISIBLE (-648 2925);
FORCEADD TAP..1
R 2
(-650 3025);
FORCEPROP 3 LASTPIN (-600 3025) SIG_NAME M_H_CPU1_SA_DQ<15>
J 0
(-590 3035);
DISPLAY 0.659574 (-590 3035);
PAINT MONO (-590 3035);
DISPLAY INVISIBLE (-590 3035);
FORCEPROP 1 LASTPIN (-600 3025) BN 15
J 2
(-588 3033);
DISPLAY 0.680851 (-588 3033);
PAINT GREEN (-588 3033);
FORCEPROP 2 LAST CDS_LIB standard
J 0
(-650 3025);
DISPLAY INVISIBLE (-650 3025);
FORCEPROP 1 LAST BODY_TYPE PLUMBING
J 2
(-650 3075);
DISPLAY 0.872340 (-650 3075);
PAINT GREEN (-650 3075);
DISPLAY INVISIBLE (-650 3075);
FORCEPROP 1 LAST HDL_TAP TRUE
J 2
(-975 2900);
DISPLAY 0.872340 (-975 2900);
DISPLAY INVISIBLE (-975 2900);
FORCEPROP 1 LAST PATH I74
J 2
(-648 3025);
DISPLAY 0.872340 (-648 3025);
PAINT GREEN (-648 3025);
DISPLAY INVISIBLE (-648 3025);
FORCEADD TAP..1
R 2
(-650 3075);
FORCEPROP 3 LASTPIN (-600 3075) SIG_NAME M_H_CPU1_SA_DQ<16>
J 0
(-590 3085);
DISPLAY 0.659574 (-590 3085);
PAINT MONO (-590 3085);
DISPLAY INVISIBLE (-590 3085);
FORCEPROP 1 LASTPIN (-600 3075) BN 16
J 2
(-588 3083);
DISPLAY 0.680851 (-588 3083);
PAINT GREEN (-588 3083);
FORCEPROP 2 LAST CDS_LIB standard
J 0
(-650 3075);
DISPLAY INVISIBLE (-650 3075);
FORCEPROP 1 LAST BODY_TYPE PLUMBING
J 2
(-650 3125);
DISPLAY 0.872340 (-650 3125);
PAINT GREEN (-650 3125);
DISPLAY INVISIBLE (-650 3125);
FORCEPROP 1 LAST HDL_TAP TRUE
J 2
(-975 2950);
DISPLAY 0.872340 (-975 2950);
DISPLAY INVISIBLE (-975 2950);
FORCEPROP 1 LAST PATH I75
J 2
(-648 3075);
DISPLAY 0.872340 (-648 3075);
PAINT GREEN (-648 3075);
DISPLAY INVISIBLE (-648 3075);
FORCEADD TAP..1
R 2
(-650 3125);
FORCEPROP 3 LASTPIN (-600 3125) SIG_NAME M_H_CPU1_SA_DQ<17>
J 0
(-590 3135);
DISPLAY 0.659574 (-590 3135);
PAINT MONO (-590 3135);
DISPLAY INVISIBLE (-590 3135);
FORCEPROP 1 LASTPIN (-600 3125) BN 17
J 2
(-588 3133);
DISPLAY 0.680851 (-588 3133);
PAINT GREEN (-588 3133);
FORCEPROP 2 LAST CDS_LIB standard
J 0
(-650 3125);
DISPLAY INVISIBLE (-650 3125);
FORCEPROP 1 LAST BODY_TYPE PLUMBING
J 2
(-650 3175);
DISPLAY 0.872340 (-650 3175);
PAINT GREEN (-650 3175);
DISPLAY INVISIBLE (-650 3175);
FORCEPROP 1 LAST HDL_TAP TRUE
J 2
(-975 3000);
DISPLAY 0.872340 (-975 3000);
DISPLAY INVISIBLE (-975 3000);
FORCEPROP 1 LAST PATH I76
J 2
(-648 3125);
DISPLAY 0.872340 (-648 3125);
PAINT GREEN (-648 3125);
DISPLAY INVISIBLE (-648 3125);
FORCEADD TAP..1
R 2
(-650 3225);
FORCEPROP 3 LASTPIN (-600 3225) SIG_NAME M_H_CPU1_SA_DQ<19>
J 0
(-590 3235);
DISPLAY 0.659574 (-590 3235);
PAINT MONO (-590 3235);
DISPLAY INVISIBLE (-590 3235);
FORCEPROP 1 LASTPIN (-600 3225) BN 19
J 2
(-588 3233);
DISPLAY 0.680851 (-588 3233);
PAINT GREEN (-588 3233);
FORCEPROP 2 LAST CDS_LIB standard
J 0
(-650 3225);
DISPLAY INVISIBLE (-650 3225);
FORCEPROP 1 LAST BODY_TYPE PLUMBING
J 2
(-650 3275);
DISPLAY 0.872340 (-650 3275);
PAINT GREEN (-650 3275);
DISPLAY INVISIBLE (-650 3275);
FORCEPROP 1 LAST HDL_TAP TRUE
J 2
(-975 3100);
DISPLAY 0.872340 (-975 3100);
DISPLAY INVISIBLE (-975 3100);
FORCEPROP 1 LAST PATH I77
J 2
(-648 3225);
DISPLAY 0.872340 (-648 3225);
PAINT GREEN (-648 3225);
DISPLAY INVISIBLE (-648 3225);
FORCEADD TAP..1
R 2
(-650 3175);
FORCEPROP 3 LASTPIN (-600 3175) SIG_NAME M_H_CPU1_SA_DQ<18>
J 0
(-590 3185);
DISPLAY 0.659574 (-590 3185);
PAINT MONO (-590 3185);
DISPLAY INVISIBLE (-590 3185);
FORCEPROP 1 LASTPIN (-600 3175) BN 18
J 2
(-588 3183);
DISPLAY 0.680851 (-588 3183);
PAINT GREEN (-588 3183);
FORCEPROP 2 LAST CDS_LIB standard
J 0
(-650 3175);
DISPLAY INVISIBLE (-650 3175);
FORCEPROP 1 LAST BODY_TYPE PLUMBING
J 2
(-650 3225);
DISPLAY 0.872340 (-650 3225);
PAINT GREEN (-650 3225);
DISPLAY INVISIBLE (-650 3225);
FORCEPROP 1 LAST HDL_TAP TRUE
J 2
(-975 3050);
DISPLAY 0.872340 (-975 3050);
DISPLAY INVISIBLE (-975 3050);
FORCEPROP 1 LAST PATH I78
J 2
(-648 3175);
DISPLAY 0.872340 (-648 3175);
PAINT GREEN (-648 3175);
DISPLAY INVISIBLE (-648 3175);
FORCEADD TAP..1
R 2
(-650 3275);
FORCEPROP 3 LASTPIN (-600 3275) SIG_NAME M_H_CPU1_SA_DQ<20>
J 0
(-590 3285);
DISPLAY 0.659574 (-590 3285);
PAINT MONO (-590 3285);
DISPLAY INVISIBLE (-590 3285);
FORCEPROP 1 LASTPIN (-600 3275) BN 20
J 2
(-588 3283);
DISPLAY 0.680851 (-588 3283);
PAINT GREEN (-588 3283);
FORCEPROP 2 LAST CDS_LIB standard
J 0
(-650 3275);
DISPLAY INVISIBLE (-650 3275);
FORCEPROP 1 LAST BODY_TYPE PLUMBING
J 2
(-650 3325);
DISPLAY 0.872340 (-650 3325);
PAINT GREEN (-650 3325);
DISPLAY INVISIBLE (-650 3325);
FORCEPROP 1 LAST HDL_TAP TRUE
J 2
(-975 3150);
DISPLAY 0.872340 (-975 3150);
DISPLAY INVISIBLE (-975 3150);
FORCEPROP 1 LAST PATH I79
J 2
(-648 3275);
DISPLAY 0.872340 (-648 3275);
PAINT GREEN (-648 3275);
DISPLAY INVISIBLE (-648 3275);
FORCEADD TAP..1
R 2
(-650 -275);
FORCEPROP 3 LASTPIN (-600 -275) SIG_NAME M_H_CPU1_CLK_DP<0>
J 0
(-590 -265);
DISPLAY 0.659574 (-590 -265);
PAINT MONO (-590 -265);
DISPLAY INVISIBLE (-590 -265);
FORCEPROP 1 LASTPIN (-600 -275) BN 0
J 2
(-588 -267);
DISPLAY 0.680851 (-588 -267);
PAINT GREEN (-588 -267);
FORCEPROP 2 LAST CDS_LIB standard
J 0
(-650 -275);
DISPLAY INVISIBLE (-650 -275);
FORCEPROP 1 LAST BODY_TYPE PLUMBING
J 2
(-650 -225);
DISPLAY 0.872340 (-650 -225);
PAINT GREEN (-650 -225);
DISPLAY INVISIBLE (-650 -225);
FORCEPROP 1 LAST HDL_TAP TRUE
J 2
(-975 -400);
DISPLAY 0.872340 (-975 -400);
DISPLAY INVISIBLE (-975 -400);
FORCEPROP 1 LAST PATH I8
J 2
(-648 -275);
DISPLAY 0.872340 (-648 -275);
PAINT GREEN (-648 -275);
DISPLAY INVISIBLE (-648 -275);
FORCEADD TAP..1
R 2
(-650 3375);
FORCEPROP 3 LASTPIN (-600 3375) SIG_NAME M_H_CPU1_SA_DQ<22>
J 0
(-590 3385);
DISPLAY 0.659574 (-590 3385);
PAINT MONO (-590 3385);
DISPLAY INVISIBLE (-590 3385);
FORCEPROP 1 LASTPIN (-600 3375) BN 22
J 2
(-588 3383);
DISPLAY 0.680851 (-588 3383);
PAINT GREEN (-588 3383);
FORCEPROP 2 LAST CDS_LIB standard
J 0
(-650 3375);
DISPLAY INVISIBLE (-650 3375);
FORCEPROP 1 LAST BODY_TYPE PLUMBING
J 2
(-650 3425);
DISPLAY 0.872340 (-650 3425);
PAINT GREEN (-650 3425);
DISPLAY INVISIBLE (-650 3425);
FORCEPROP 1 LAST HDL_TAP TRUE
J 2
(-975 3250);
DISPLAY 0.872340 (-975 3250);
DISPLAY INVISIBLE (-975 3250);
FORCEPROP 1 LAST PATH I80
J 2
(-648 3375);
DISPLAY 0.872340 (-648 3375);
PAINT GREEN (-648 3375);
DISPLAY INVISIBLE (-648 3375);
FORCEADD TAP..1
R 2
(-650 3325);
FORCEPROP 3 LASTPIN (-600 3325) SIG_NAME M_H_CPU1_SA_DQ<21>
J 0
(-590 3335);
DISPLAY 0.659574 (-590 3335);
PAINT MONO (-590 3335);
DISPLAY INVISIBLE (-590 3335);
FORCEPROP 1 LASTPIN (-600 3325) BN 21
J 2
(-588 3333);
DISPLAY 0.680851 (-588 3333);
PAINT GREEN (-588 3333);
FORCEPROP 2 LAST CDS_LIB standard
J 0
(-650 3325);
DISPLAY INVISIBLE (-650 3325);
FORCEPROP 1 LAST BODY_TYPE PLUMBING
J 2
(-650 3375);
DISPLAY 0.872340 (-650 3375);
PAINT GREEN (-650 3375);
DISPLAY INVISIBLE (-650 3375);
FORCEPROP 1 LAST HDL_TAP TRUE
J 2
(-975 3200);
DISPLAY 0.872340 (-975 3200);
DISPLAY INVISIBLE (-975 3200);
FORCEPROP 1 LAST PATH I81
J 2
(-648 3325);
DISPLAY 0.872340 (-648 3325);
PAINT GREEN (-648 3325);
DISPLAY INVISIBLE (-648 3325);
FORCEADD OFFPAGE..3
R 2
(-1675 3850);
FORCEPROP 2 LAST $XR1 113 
J 0
(-2105 3850);
DISPLAY 0.638298 (-2105 3850);
PAINT MONO (-2105 3850);
FORCEPROP 2 LAST $XR0 112 
J 0
(-1985 3850);
DISPLAY 0.638298 (-1985 3850);
PAINT MONO (-1985 3850);
FORCEPROP 2 LAST CDS_LIB standard
J 0
(-1675 3850);
DISPLAY INVISIBLE (-1675 3850);
FORCEPROP 1 LAST OFFPAGE TRUE
J 2
(-2000 3725);
DISPLAY 0.872340 (-2000 3725);
DISPLAY INVISIBLE (-2000 3725);
FORCEPROP 1 LAST COMMENT_BODY TRUE
J 2
(-1625 3750);
DISPLAY 0.872340 (-1625 3750);
PAINT GREEN (-1625 3750);
DISPLAY INVISIBLE (-1625 3750);
FORCEPROP 2 LAST PATH I82
J 0
(-1625 3925);
DISPLAY 1.021277 (-1625 3925);
DISPLAY INVISIBLE (-1625 3925);
FORCEADD TAP..1
R 2
(-650 3475);
FORCEPROP 3 LASTPIN (-600 3475) SIG_NAME M_H_CPU1_SA_DQ<24>
J 0
(-590 3485);
DISPLAY 0.659574 (-590 3485);
PAINT MONO (-590 3485);
DISPLAY INVISIBLE (-590 3485);
FORCEPROP 1 LASTPIN (-600 3475) BN 24
J 2
(-588 3483);
DISPLAY 0.680851 (-588 3483);
PAINT GREEN (-588 3483);
FORCEPROP 2 LAST CDS_LIB standard
J 0
(-650 3475);
DISPLAY INVISIBLE (-650 3475);
FORCEPROP 1 LAST BODY_TYPE PLUMBING
J 2
(-650 3525);
DISPLAY 0.872340 (-650 3525);
PAINT GREEN (-650 3525);
DISPLAY INVISIBLE (-650 3525);
FORCEPROP 1 LAST HDL_TAP TRUE
J 2
(-975 3350);
DISPLAY 0.872340 (-975 3350);
DISPLAY INVISIBLE (-975 3350);
FORCEPROP 1 LAST PATH I83
J 2
(-648 3475);
DISPLAY 0.872340 (-648 3475);
PAINT GREEN (-648 3475);
DISPLAY INVISIBLE (-648 3475);
FORCEADD TAP..1
R 2
(-650 3425);
FORCEPROP 3 LASTPIN (-600 3425) SIG_NAME M_H_CPU1_SA_DQ<23>
J 0
(-590 3435);
DISPLAY 0.659574 (-590 3435);
PAINT MONO (-590 3435);
DISPLAY INVISIBLE (-590 3435);
FORCEPROP 1 LASTPIN (-600 3425) BN 23
J 2
(-588 3433);
DISPLAY 0.680851 (-588 3433);
PAINT GREEN (-588 3433);
FORCEPROP 2 LAST CDS_LIB standard
J 0
(-650 3425);
DISPLAY INVISIBLE (-650 3425);
FORCEPROP 1 LAST BODY_TYPE PLUMBING
J 2
(-650 3475);
DISPLAY 0.872340 (-650 3475);
PAINT GREEN (-650 3475);
DISPLAY INVISIBLE (-650 3475);
FORCEPROP 1 LAST HDL_TAP TRUE
J 2
(-975 3300);
DISPLAY 0.872340 (-975 3300);
DISPLAY INVISIBLE (-975 3300);
FORCEPROP 1 LAST PATH I84
J 2
(-648 3425);
DISPLAY 0.872340 (-648 3425);
PAINT GREEN (-648 3425);
DISPLAY INVISIBLE (-648 3425);
FORCEADD TAP..1
R 2
(-650 3525);
FORCEPROP 3 LASTPIN (-600 3525) SIG_NAME M_H_CPU1_SA_DQ<25>
J 0
(-590 3535);
DISPLAY 0.659574 (-590 3535);
PAINT MONO (-590 3535);
DISPLAY INVISIBLE (-590 3535);
FORCEPROP 1 LASTPIN (-600 3525) BN 25
J 2
(-588 3533);
DISPLAY 0.680851 (-588 3533);
PAINT GREEN (-588 3533);
FORCEPROP 2 LAST CDS_LIB standard
J 0
(-650 3525);
DISPLAY INVISIBLE (-650 3525);
FORCEPROP 1 LAST BODY_TYPE PLUMBING
J 2
(-650 3575);
DISPLAY 0.872340 (-650 3575);
PAINT GREEN (-650 3575);
DISPLAY INVISIBLE (-650 3575);
FORCEPROP 1 LAST HDL_TAP TRUE
J 2
(-975 3400);
DISPLAY 0.872340 (-975 3400);
DISPLAY INVISIBLE (-975 3400);
FORCEPROP 1 LAST PATH I85
J 2
(-648 3525);
DISPLAY 0.872340 (-648 3525);
PAINT GREEN (-648 3525);
DISPLAY INVISIBLE (-648 3525);
FORCEADD TAP..1
R 2
(-650 3625);
FORCEPROP 3 LASTPIN (-600 3625) SIG_NAME M_H_CPU1_SA_DQ<27>
J 0
(-590 3635);
DISPLAY 0.659574 (-590 3635);
PAINT MONO (-590 3635);
DISPLAY INVISIBLE (-590 3635);
FORCEPROP 1 LASTPIN (-600 3625) BN 27
J 2
(-588 3633);
DISPLAY 0.680851 (-588 3633);
PAINT GREEN (-588 3633);
FORCEPROP 2 LAST CDS_LIB standard
J 0
(-650 3625);
DISPLAY INVISIBLE (-650 3625);
FORCEPROP 1 LAST BODY_TYPE PLUMBING
J 2
(-650 3675);
DISPLAY 0.872340 (-650 3675);
PAINT GREEN (-650 3675);
DISPLAY INVISIBLE (-650 3675);
FORCEPROP 1 LAST HDL_TAP TRUE
J 2
(-975 3500);
DISPLAY 0.872340 (-975 3500);
DISPLAY INVISIBLE (-975 3500);
FORCEPROP 1 LAST PATH I86
J 2
(-648 3625);
DISPLAY 0.872340 (-648 3625);
PAINT GREEN (-648 3625);
DISPLAY INVISIBLE (-648 3625);
FORCEADD TAP..1
R 2
(-650 3575);
FORCEPROP 3 LASTPIN (-600 3575) SIG_NAME M_H_CPU1_SA_DQ<26>
J 0
(-590 3585);
DISPLAY 0.659574 (-590 3585);
PAINT MONO (-590 3585);
DISPLAY INVISIBLE (-590 3585);
FORCEPROP 1 LASTPIN (-600 3575) BN 26
J 2
(-588 3583);
DISPLAY 0.680851 (-588 3583);
PAINT GREEN (-588 3583);
FORCEPROP 2 LAST CDS_LIB standard
J 0
(-650 3575);
DISPLAY INVISIBLE (-650 3575);
FORCEPROP 1 LAST BODY_TYPE PLUMBING
J 2
(-650 3625);
DISPLAY 0.872340 (-650 3625);
PAINT GREEN (-650 3625);
DISPLAY INVISIBLE (-650 3625);
FORCEPROP 1 LAST HDL_TAP TRUE
J 2
(-975 3450);
DISPLAY 0.872340 (-975 3450);
DISPLAY INVISIBLE (-975 3450);
FORCEPROP 1 LAST PATH I87
J 2
(-648 3575);
DISPLAY 0.872340 (-648 3575);
PAINT GREEN (-648 3575);
DISPLAY INVISIBLE (-648 3575);
FORCEADD TAP..1
R 2
(-650 3675);
FORCEPROP 3 LASTPIN (-600 3675) SIG_NAME M_H_CPU1_SA_DQ<28>
J 0
(-590 3685);
DISPLAY 0.659574 (-590 3685);
PAINT MONO (-590 3685);
DISPLAY INVISIBLE (-590 3685);
FORCEPROP 1 LASTPIN (-600 3675) BN 28
J 2
(-588 3683);
DISPLAY 0.680851 (-588 3683);
PAINT GREEN (-588 3683);
FORCEPROP 2 LAST CDS_LIB standard
J 0
(-650 3675);
DISPLAY INVISIBLE (-650 3675);
FORCEPROP 1 LAST BODY_TYPE PLUMBING
J 2
(-650 3725);
DISPLAY 0.872340 (-650 3725);
PAINT GREEN (-650 3725);
DISPLAY INVISIBLE (-650 3725);
FORCEPROP 1 LAST HDL_TAP TRUE
J 2
(-975 3550);
DISPLAY 0.872340 (-975 3550);
DISPLAY INVISIBLE (-975 3550);
FORCEPROP 1 LAST PATH I88
J 2
(-648 3675);
DISPLAY 0.872340 (-648 3675);
PAINT GREEN (-648 3675);
DISPLAY INVISIBLE (-648 3675);
FORCEADD TAP..1
R 2
(-650 3725);
FORCEPROP 3 LASTPIN (-600 3725) SIG_NAME M_H_CPU1_SA_DQ<29>
J 0
(-590 3735);
DISPLAY 0.659574 (-590 3735);
PAINT MONO (-590 3735);
DISPLAY INVISIBLE (-590 3735);
FORCEPROP 1 LASTPIN (-600 3725) BN 29
J 2
(-588 3733);
DISPLAY 0.680851 (-588 3733);
PAINT GREEN (-588 3733);
FORCEPROP 2 LAST CDS_LIB standard
J 0
(-650 3725);
DISPLAY INVISIBLE (-650 3725);
FORCEPROP 1 LAST BODY_TYPE PLUMBING
J 2
(-650 3775);
DISPLAY 0.872340 (-650 3775);
PAINT GREEN (-650 3775);
DISPLAY INVISIBLE (-650 3775);
FORCEPROP 1 LAST HDL_TAP TRUE
J 2
(-975 3600);
DISPLAY 0.872340 (-975 3600);
DISPLAY INVISIBLE (-975 3600);
FORCEPROP 1 LAST PATH I89
J 2
(-648 3725);
DISPLAY 0.872340 (-648 3725);
PAINT GREEN (-648 3725);
DISPLAY INVISIBLE (-648 3725);
FORCEADD TAP..1
R 2
(-650 -225);
FORCEPROP 3 LASTPIN (-600 -225) SIG_NAME M_H_CPU1_CLK_DP<1>
J 0
(-590 -215);
DISPLAY 0.659574 (-590 -215);
PAINT MONO (-590 -215);
DISPLAY INVISIBLE (-590 -215);
FORCEPROP 1 LASTPIN (-600 -225) BN 1
J 2
(-588 -217);
DISPLAY 0.680851 (-588 -217);
PAINT GREEN (-588 -217);
FORCEPROP 2 LAST CDS_LIB standard
J 0
(-650 -225);
DISPLAY INVISIBLE (-650 -225);
FORCEPROP 1 LAST BODY_TYPE PLUMBING
J 2
(-650 -175);
DISPLAY 0.872340 (-650 -175);
PAINT GREEN (-650 -175);
DISPLAY INVISIBLE (-650 -175);
FORCEPROP 1 LAST HDL_TAP TRUE
J 2
(-975 -350);
DISPLAY 0.872340 (-975 -350);
DISPLAY INVISIBLE (-975 -350);
FORCEPROP 1 LAST PATH I9
J 2
(-648 -225);
DISPLAY 0.872340 (-648 -225);
PAINT GREEN (-648 -225);
DISPLAY INVISIBLE (-648 -225);
FORCEADD TAP..1
R 2
(-650 3775);
FORCEPROP 3 LASTPIN (-600 3775) SIG_NAME M_H_CPU1_SA_DQ<30>
J 0
(-590 3785);
DISPLAY 0.659574 (-590 3785);
PAINT MONO (-590 3785);
DISPLAY INVISIBLE (-590 3785);
FORCEPROP 1 LASTPIN (-600 3775) BN 30
J 2
(-588 3783);
DISPLAY 0.680851 (-588 3783);
PAINT GREEN (-588 3783);
FORCEPROP 2 LAST CDS_LIB standard
J 0
(-650 3775);
DISPLAY INVISIBLE (-650 3775);
FORCEPROP 1 LAST BODY_TYPE PLUMBING
J 2
(-650 3825);
DISPLAY 0.872340 (-650 3825);
PAINT GREEN (-650 3825);
DISPLAY INVISIBLE (-650 3825);
FORCEPROP 1 LAST HDL_TAP TRUE
J 2
(-975 3650);
DISPLAY 0.872340 (-975 3650);
DISPLAY INVISIBLE (-975 3650);
FORCEPROP 1 LAST PATH I90
J 2
(-648 3775);
DISPLAY 0.872340 (-648 3775);
PAINT GREEN (-648 3775);
DISPLAY INVISIBLE (-648 3775);
FORCEADD TAP..1
R 2
(-650 3825);
FORCEPROP 3 LASTPIN (-600 3825) SIG_NAME M_H_CPU1_SA_DQ<31>
J 0
(-590 3835);
DISPLAY 0.659574 (-590 3835);
PAINT MONO (-590 3835);
DISPLAY INVISIBLE (-590 3835);
FORCEPROP 1 LASTPIN (-600 3825) BN 31
J 2
(-588 3833);
DISPLAY 0.680851 (-588 3833);
PAINT GREEN (-588 3833);
FORCEPROP 2 LAST CDS_LIB standard
J 0
(-650 3825);
DISPLAY INVISIBLE (-650 3825);
FORCEPROP 1 LAST BODY_TYPE PLUMBING
J 2
(-650 3875);
DISPLAY 0.872340 (-650 3875);
PAINT GREEN (-650 3875);
DISPLAY INVISIBLE (-650 3875);
FORCEPROP 1 LAST HDL_TAP TRUE
J 2
(-975 3700);
DISPLAY 0.872340 (-975 3700);
DISPLAY INVISIBLE (-975 3700);
FORCEPROP 1 LAST PATH I91
J 2
(-648 3825);
DISPLAY 0.872340 (-648 3825);
PAINT GREEN (-648 3825);
DISPLAY INVISIBLE (-648 3825);
FORCEADD TAP..1
(2775 75);
FORCEPROP 3 LASTPIN (2725 75) SIG_NAME M_H_CPU1_SB_CS_N<0>
J 0
(2735 85);
DISPLAY 0.659574 (2735 85);
PAINT MONO (2735 85);
DISPLAY INVISIBLE (2735 85);
FORCEPROP 1 LASTPIN (2725 75) BN 0
J 0
(2713 83);
DISPLAY 0.680851 (2713 83);
PAINT GREEN (2713 83);
FORCEPROP 2 LAST CDS_LIB standard
J 0
(2775 75);
DISPLAY INVISIBLE (2775 75);
FORCEPROP 1 LAST BODY_TYPE PLUMBING
J 0
(2775 125);
DISPLAY 0.872340 (2775 125);
PAINT GREEN (2775 125);
DISPLAY INVISIBLE (2775 125);
FORCEPROP 1 LAST HDL_TAP TRUE
J 0
(3100 -50);
DISPLAY 0.872340 (3100 -50);
DISPLAY INVISIBLE (3100 -50);
FORCEPROP 1 LAST PATH I92
J 0
(2773 75);
DISPLAY 0.872340 (2773 75);
PAINT GREEN (2773 75);
DISPLAY INVISIBLE (2773 75);
FORCEADD TAP..1
(2775 225);
FORCEPROP 3 LASTPIN (2725 225) SIG_NAME M_H_CPU1_SB_CS_N<3>
J 0
(2735 235);
DISPLAY 0.659574 (2735 235);
PAINT MONO (2735 235);
DISPLAY INVISIBLE (2735 235);
FORCEPROP 1 LASTPIN (2725 225) BN 3
J 0
(2713 233);
DISPLAY 0.680851 (2713 233);
PAINT GREEN (2713 233);
FORCEPROP 2 LAST CDS_LIB standard
J 0
(2775 225);
DISPLAY INVISIBLE (2775 225);
FORCEPROP 1 LAST BODY_TYPE PLUMBING
J 0
(2775 275);
DISPLAY 0.872340 (2775 275);
PAINT GREEN (2775 275);
DISPLAY INVISIBLE (2775 275);
FORCEPROP 1 LAST HDL_TAP TRUE
J 0
(3100 100);
DISPLAY 0.872340 (3100 100);
DISPLAY INVISIBLE (3100 100);
FORCEPROP 1 LAST PATH I93
J 0
(2773 225);
DISPLAY 0.872340 (2773 225);
PAINT GREEN (2773 225);
DISPLAY INVISIBLE (2773 225);
FORCEADD TAP..1
(2775 125);
FORCEPROP 3 LASTPIN (2725 125) SIG_NAME M_H_CPU1_SB_CS_N<1>
J 0
(2735 135);
DISPLAY 0.659574 (2735 135);
PAINT MONO (2735 135);
DISPLAY INVISIBLE (2735 135);
FORCEPROP 1 LASTPIN (2725 125) BN 1
J 0
(2713 133);
DISPLAY 0.680851 (2713 133);
PAINT GREEN (2713 133);
FORCEPROP 2 LAST CDS_LIB standard
J 0
(2775 125);
DISPLAY INVISIBLE (2775 125);
FORCEPROP 1 LAST BODY_TYPE PLUMBING
J 0
(2775 175);
DISPLAY 0.872340 (2775 175);
PAINT GREEN (2775 175);
DISPLAY INVISIBLE (2775 175);
FORCEPROP 1 LAST HDL_TAP TRUE
J 0
(3100 0);
DISPLAY 0.872340 (3100 0);
DISPLAY INVISIBLE (3100 0);
FORCEPROP 1 LAST PATH I94
J 0
(2773 125);
DISPLAY 0.872340 (2773 125);
PAINT GREEN (2773 125);
DISPLAY INVISIBLE (2773 125);
FORCEADD TAP..1
(2775 175);
FORCEPROP 3 LASTPIN (2725 175) SIG_NAME M_H_CPU1_SB_CS_N<2>
J 0
(2735 185);
DISPLAY 0.659574 (2735 185);
PAINT MONO (2735 185);
DISPLAY INVISIBLE (2735 185);
FORCEPROP 1 LASTPIN (2725 175) BN 2
J 0
(2713 183);
DISPLAY 0.680851 (2713 183);
PAINT GREEN (2713 183);
FORCEPROP 2 LAST CDS_LIB standard
J 0
(2775 175);
DISPLAY INVISIBLE (2775 175);
FORCEPROP 1 LAST BODY_TYPE PLUMBING
J 0
(2775 225);
DISPLAY 0.872340 (2775 225);
PAINT GREEN (2775 225);
DISPLAY INVISIBLE (2775 225);
FORCEPROP 1 LAST HDL_TAP TRUE
J 0
(3100 50);
DISPLAY 0.872340 (3100 50);
DISPLAY INVISIBLE (3100 50);
FORCEPROP 1 LAST PATH I95
J 0
(2773 175);
DISPLAY 0.872340 (2773 175);
PAINT GREEN (2773 175);
DISPLAY INVISIBLE (2773 175);
FORCEADD TAP..1
(2775 375);
FORCEPROP 3 LASTPIN (2725 375) SIG_NAME M_H_CPU1_SA_CS_N<0>
J 0
(2735 385);
DISPLAY 0.659574 (2735 385);
PAINT MONO (2735 385);
DISPLAY INVISIBLE (2735 385);
FORCEPROP 1 LASTPIN (2725 375) BN 0
J 0
(2713 383);
DISPLAY 0.680851 (2713 383);
PAINT GREEN (2713 383);
FORCEPROP 2 LAST CDS_LIB standard
J 0
(2775 375);
DISPLAY INVISIBLE (2775 375);
FORCEPROP 1 LAST BODY_TYPE PLUMBING
J 0
(2775 425);
DISPLAY 0.872340 (2775 425);
PAINT GREEN (2775 425);
DISPLAY INVISIBLE (2775 425);
FORCEPROP 1 LAST HDL_TAP TRUE
J 0
(3100 250);
DISPLAY 0.872340 (3100 250);
DISPLAY INVISIBLE (3100 250);
FORCEPROP 1 LAST PATH I96
J 0
(2773 375);
DISPLAY 0.872340 (2773 375);
PAINT GREEN (2773 375);
DISPLAY INVISIBLE (2773 375);
FORCEADD TAP..1
(2775 525);
FORCEPROP 3 LASTPIN (2725 525) SIG_NAME M_H_CPU1_SA_CS_N<3>
J 0
(2735 535);
DISPLAY 0.659574 (2735 535);
PAINT MONO (2735 535);
DISPLAY INVISIBLE (2735 535);
FORCEPROP 1 LASTPIN (2725 525) BN 3
J 0
(2713 533);
DISPLAY 0.680851 (2713 533);
PAINT GREEN (2713 533);
FORCEPROP 2 LAST CDS_LIB standard
J 0
(2775 525);
DISPLAY INVISIBLE (2775 525);
FORCEPROP 1 LAST BODY_TYPE PLUMBING
J 0
(2775 575);
DISPLAY 0.872340 (2775 575);
PAINT GREEN (2775 575);
DISPLAY INVISIBLE (2775 575);
FORCEPROP 1 LAST HDL_TAP TRUE
J 0
(3100 400);
DISPLAY 0.872340 (3100 400);
DISPLAY INVISIBLE (3100 400);
FORCEPROP 1 LAST PATH I97
J 0
(2773 525);
DISPLAY 0.872340 (2773 525);
PAINT GREEN (2773 525);
DISPLAY INVISIBLE (2773 525);
FORCEADD TAP..1
(2775 475);
FORCEPROP 3 LASTPIN (2725 475) SIG_NAME M_H_CPU1_SA_CS_N<2>
J 0
(2735 485);
DISPLAY 0.659574 (2735 485);
PAINT MONO (2735 485);
DISPLAY INVISIBLE (2735 485);
FORCEPROP 1 LASTPIN (2725 475) BN 2
J 0
(2713 483);
DISPLAY 0.680851 (2713 483);
PAINT GREEN (2713 483);
FORCEPROP 2 LAST CDS_LIB standard
J 0
(2775 475);
DISPLAY INVISIBLE (2775 475);
FORCEPROP 1 LAST BODY_TYPE PLUMBING
J 0
(2775 525);
DISPLAY 0.872340 (2775 525);
PAINT GREEN (2775 525);
DISPLAY INVISIBLE (2775 525);
FORCEPROP 1 LAST HDL_TAP TRUE
J 0
(3100 350);
DISPLAY 0.872340 (3100 350);
DISPLAY INVISIBLE (3100 350);
FORCEPROP 1 LAST PATH I98
J 0
(2773 475);
DISPLAY 0.872340 (2773 475);
PAINT GREEN (2773 475);
DISPLAY INVISIBLE (2773 475);
FORCEADD TAP..1
(2775 425);
FORCEPROP 3 LASTPIN (2725 425) SIG_NAME M_H_CPU1_SA_CS_N<1>
J 0
(2735 435);
DISPLAY 0.659574 (2735 435);
PAINT MONO (2735 435);
DISPLAY INVISIBLE (2735 435);
FORCEPROP 1 LASTPIN (2725 425) BN 1
J 0
(2713 433);
DISPLAY 0.680851 (2713 433);
PAINT GREEN (2713 433);
FORCEPROP 2 LAST CDS_LIB standard
J 0
(2775 425);
DISPLAY INVISIBLE (2775 425);
FORCEPROP 1 LAST BODY_TYPE PLUMBING
J 0
(2775 475);
DISPLAY 0.872340 (2775 475);
PAINT GREEN (2775 475);
DISPLAY INVISIBLE (2775 475);
FORCEPROP 1 LAST HDL_TAP TRUE
J 0
(3100 300);
DISPLAY 0.872340 (3100 300);
DISPLAY INVISIBLE (3100 300);
FORCEPROP 1 LAST PATH I99
J 0
(2773 425);
DISPLAY 0.872340 (2773 425);
PAINT GREEN (2773 425);
DISPLAY INVISIBLE (2773 425);
FORCEADD QUANTA_TITLE_BLOCK_C..1
(5700 -1675);
FORCEPROP 0 LAST CDS_CON_LAST_MODIFIED Fri Aug 25 14:00:40 2023
J 0
(3815 -1660);
PAINT MONO (3815 -1660);
DISPLAY INVISIBLE (3815 -1660);
FORCEPROP 1 LAST CUSTOM_TXT_CDS <CON_LAST_MODIFIED>
J 0
(3815 -1660);
DISPLAY 0.978723 (3815 -1660);
FORCEPROP 2 LAST CUSTOM_TXT_CDS <XR_PAGE_TITLE>
J 0
(-2190 3575);
DISPLAY 0.638298 (-2190 3575);
PAINT PINK (-2190 3575);
DISPLAY INVISIBLE (-2190 3575);
FORCEPROP 2 LAST CUSTOM_TXT_CDS <Q_NUMBER>
J 0
(4297 -1572);
DISPLAY 1.212766 (4297 -1572);
FORCEPROP 1 LAST CUSTOM_TXT_CDS <NAME_2>
J 0
(2525 -1625);
FORCEPROP 1 LAST CUSTOM_TXT_CDS <NAME_1>
J 0
(2525 -1500);
FORCEPROP 1 LAST CUSTOM_TXT_CDS <Q_PROJ>
J 0
(3318 -1573);
DISPLAY 1.212766 (3318 -1573);
FORCEPROP 1 LAST CUSTOM_TXT_CDS <Q_REV>
J 0
(5516 -1572);
DISPLAY 1.212766 (5516 -1572);
FORCEPROP 1 LAST CUSTOM_TXT_CDS <CON_PAGE_NUM> OF <CON_TOTAL_PAGES>
J 0
(5254 -1657);
DISPLAY 0.978723 (5254 -1657);
FORCEPROP 1 LAST Q_TITLE SPR CPU1 - DDR CH H (15 OF 30)
J 0
(-3666 -1649);
DISPLAY 1.957447 (-3666 -1649);
PAINT GREEN (-3666 -1649);
FORCEPROP 1 LAST Q_DEPT 
J 1
(1937 -1626);
DISPLAY 1.957447 (1937 -1626);
PAINT GREEN (1937 -1626);
FORCEPROP 1 LAST COMMENT_BODY TRUE
J 0
(5712 -1688);
DISPLAY 0.978723 (5712 -1688);
PAINT GREEN (5712 -1688);
DISPLAY INVISIBLE (5712 -1688);
FORCEPROP 2 LAST CDS_XR_PAGE_TITLE CR-58 : @S9S_MB_2U_LIB.S9S_MB_2U(SCH_1):PAGE58
J 0
(-2190 3575);
DISPLAY 0.638298 (-2190 3575);
PAINT PINK (-2190 3575);
DISPLAY INVISIBLE (-2190 3575);
FORCEPROP 2 LAST PAGE_BORDER TRUE
J 0
(-2190 3575);
DISPLAY 0.638298 (-2190 3575);
PAINT PINK (-2190 3575);
DISPLAY INVISIBLE (-2190 3575);
FORCEPROP 1 LAST CDS_LMAN_SYM_OUTLINE -9475,6775,100,-125
J 0
(5700 -1675);
DISPLAY 0.468085 (5700 -1675);
PAINT GREEN (5700 -1675);
DISPLAY INVISIBLE (5700 -1675);
FORCEPROP 2 LAST CDS_LIB pure_quanta
J 0
(5700 -1675);
PAINT MONO (5700 -1675);
DISPLAY INVISIBLE (5700 -1675);
WIRE 17 -1 (2825 1550)(3825 1550);
FORCEPROP 2 LAST SIG_NAME M_H_CPU1_SA_CA<6:0>
J 0
(2965 1560);
DISPLAY 0.680851 (2965 1560);
PAINT WHITE (2965 1560);
WIRE 17 -1 (2825 1500)(2825 1550);
WIRE 17 -1 (2825 1450)(2825 1500);
WIRE 17 -1 (2825 1400)(2825 1450);
WIRE 17 -1 (2825 1350)(2825 1400);
WIRE 17 -1 (2825 1300)(2825 1350);
WIRE 17 -1 (2825 1250)(2825 1300);
WIRE 17 -1 (2825 550)(3825 550);
FORCEPROP 2 LAST SIG_NAME M_H_CPU1_SA_CS_N<3:0>
J 0
(2965 560);
DISPLAY 0.680851 (2965 560);
PAINT WHITE (2965 560);
WIRE 17 -1 (2825 500)(2825 550);
WIRE 17 -1 (2825 450)(2825 500);
WIRE 17 -1 (2825 400)(2825 450);
WIRE 17 -1 (2825 3300)(3825 3300);
FORCEPROP 2 LAST SIG_NAME M_H_CPU1_SA_DQS_DN<9:0>
J 0
(2965 3310);
DISPLAY 0.680851 (2965 3310);
PAINT WHITE (2965 3310);
WIRE 17 -1 (2825 3250)(2825 3300);
WIRE 17 -1 (2825 3200)(2825 3250);
WIRE 17 -1 (2825 3150)(2825 3200);
WIRE 17 -1 (2825 3100)(2825 3150);
WIRE 17 -1 (2825 3050)(2825 3100);
WIRE 17 -1 (2825 3000)(2825 3050);
WIRE 17 -1 (2825 2950)(2825 3000);
WIRE 17 -1 (2825 2900)(2825 2950);
WIRE 17 -1 (2825 2850)(2825 2900);
WIRE 17 -1 (2825 3850)(3825 3850);
FORCEPROP 2 LAST SIG_NAME M_H_CPU1_SA_DQS_DP<9:0>
J 0
(2965 3860);
DISPLAY 0.680851 (2965 3860);
PAINT WHITE (2965 3860);
WIRE 17 -1 (2825 3800)(2825 3850);
WIRE 17 -1 (2825 3750)(2825 3800);
WIRE 17 -1 (2825 3700)(2825 3750);
WIRE 17 -1 (2825 3650)(2825 3700);
WIRE 17 -1 (2825 3600)(2825 3650);
WIRE 17 -1 (2825 3550)(2825 3600);
WIRE 17 -1 (2825 3500)(2825 3550);
WIRE 17 -1 (2825 3450)(2825 3500);
WIRE 17 -1 (2825 3400)(2825 3450);
WIRE 17 -1 (2825 1050)(3825 1050);
FORCEPROP 2 LAST SIG_NAME M_H_CPU1_SB_CA<6:0>
J 0
(2965 1060);
DISPLAY 0.680851 (2965 1060);
PAINT WHITE (2965 1060);
WIRE 17 -1 (2825 1000)(2825 1050);
WIRE 17 -1 (2825 950)(2825 1000);
WIRE 17 -1 (2825 900)(2825 950);
WIRE 17 -1 (2825 850)(2825 900);
WIRE 17 -1 (2825 800)(2825 850);
WIRE 17 -1 (2825 750)(2825 800);
WIRE 17 -1 (2825 250)(3825 250);
FORCEPROP 2 LAST SIG_NAME M_H_CPU1_SB_CS_N<3:0>
J 0
(2965 260);
DISPLAY 0.680851 (2965 260);
PAINT WHITE (2965 260);
WIRE 17 -1 (2825 200)(2825 250);
WIRE 17 -1 (2825 150)(2825 200);
WIRE 17 -1 (2825 100)(2825 150);
WIRE 17 -1 (2825 2150)(3825 2150);
FORCEPROP 2 LAST SIG_NAME M_H_CPU1_SB_DQS_DN<9:0>
J 0
(2965 2160);
DISPLAY 0.680851 (2965 2160);
PAINT WHITE (2965 2160);
WIRE 17 -1 (2825 2100)(2825 2150);
WIRE 17 -1 (2825 2050)(2825 2100);
WIRE 17 -1 (2825 2000)(2825 2050);
WIRE 17 -1 (2825 1950)(2825 2000);
WIRE 17 -1 (2825 1900)(2825 1950);
WIRE 17 -1 (2825 1850)(2825 1900);
WIRE 17 -1 (2825 1800)(2825 1850);
WIRE 17 -1 (2825 1750)(2825 1800);
WIRE 17 -1 (2825 1700)(2825 1750);
WIRE 17 -1 (2825 2700)(3825 2700);
FORCEPROP 2 LAST SIG_NAME M_H_CPU1_SB_DQS_DP<9:0>
J 0
(2965 2710);
DISPLAY 0.680851 (2965 2710);
PAINT WHITE (2965 2710);
WIRE 17 -1 (2825 2650)(2825 2700);
WIRE 17 -1 (2825 2600)(2825 2650);
WIRE 17 -1 (2825 2550)(2825 2600);
WIRE 17 -1 (2825 2500)(2825 2550);
WIRE 17 -1 (2825 2450)(2825 2500);
WIRE 17 -1 (2825 2400)(2825 2450);
WIRE 17 -1 (2825 2350)(2825 2400);
WIRE 17 -1 (2825 2300)(2825 2350);
WIRE 17 -1 (2825 2250)(2825 2300);
WIRE 17 -1 (-700 -100)(-700 -50);
WIRE 17 -1 (-700 -50)(-700 0);
WIRE 17 -1 (-700 0)(-700 50);
WIRE 17 -1 (-700 50)(-700 100);
WIRE 17 -1 (-700 100)(-700 150);
WIRE 17 -1 (-700 150)(-700 200);
WIRE 17 -1 (-700 200)(-700 250);
WIRE 17 -1 (-1625 250)(-700 250);
FORCEPROP 2 LAST SIG_NAME M_H_CPU1_SB_CB<7:0>
J 0
(-1485 260);
DISPLAY 0.680851 (-1485 260);
PAINT WHITE (-1485 260);
WIRE 17 -1 (-700 300)(-700 350);
WIRE 17 -1 (-700 350)(-700 400);
WIRE 17 -1 (-700 400)(-700 450);
WIRE 17 -1 (-700 450)(-700 500);
WIRE 17 -1 (-700 500)(-700 550);
WIRE 17 -1 (-700 550)(-700 600);
WIRE 17 -1 (-700 600)(-700 650);
WIRE 17 -1 (-700 650)(-700 700);
WIRE 17 -1 (-700 700)(-700 750);
WIRE 17 -1 (-700 750)(-700 800);
WIRE 17 -1 (-700 800)(-700 850);
WIRE 17 -1 (-700 850)(-700 900);
WIRE 17 -1 (-700 900)(-700 950);
WIRE 17 -1 (-700 950)(-700 1000);
WIRE 17 -1 (-700 1000)(-700 1050);
WIRE 17 -1 (-700 1050)(-700 1100);
WIRE 17 -1 (-700 1100)(-700 1150);
WIRE 17 -1 (-700 1150)(-700 1200);
WIRE 17 -1 (-700 1200)(-700 1250);
WIRE 17 -1 (-700 1250)(-700 1300);
WIRE 17 -1 (-700 1300)(-700 1350);
WIRE 17 -1 (-700 1350)(-700 1400);
WIRE 17 -1 (-700 1400)(-700 1450);
WIRE 17 -1 (-700 1450)(-700 1500);
WIRE 17 -1 (-700 1500)(-700 1550);
WIRE 17 -1 (-700 1550)(-700 1600);
WIRE 17 -1 (-700 1600)(-700 1650);
WIRE 17 -1 (-700 1650)(-700 1700);
WIRE 17 -1 (-700 1700)(-700 1750);
WIRE 17 -1 (-700 1750)(-700 1800);
WIRE 17 -1 (-700 1800)(-700 1850);
WIRE 17 -1 (-1625 1850)(-700 1850);
FORCEPROP 2 LAST SIG_NAME M_H_CPU1_SB_DQ<31:0>
J 0
(-1485 1860);
DISPLAY 0.680851 (-1485 1860);
PAINT WHITE (-1485 1860);
WIRE 17 -1 (-700 1900)(-700 1950);
WIRE 17 -1 (-700 1950)(-700 2000);
WIRE 17 -1 (-700 2000)(-700 2050);
WIRE 17 -1 (-700 2050)(-700 2100);
WIRE 17 -1 (-700 2100)(-700 2150);
WIRE 17 -1 (-700 2150)(-700 2200);
WIRE 17 -1 (-700 2200)(-700 2250);
WIRE 17 -1 (-1625 2250)(-700 2250);
FORCEPROP 2 LAST SIG_NAME M_H_CPU1_SA_CB<7:0>
J 0
(-1485 2260);
DISPLAY 0.680851 (-1485 2260);
PAINT WHITE (-1485 2260);
WIRE 17 -1 (-700 2300)(-700 2350);
WIRE 17 -1 (-700 2350)(-700 2400);
WIRE 17 -1 (-700 2400)(-700 2450);
WIRE 17 -1 (-700 2450)(-700 2500);
WIRE 17 -1 (-700 2500)(-700 2550);
WIRE 17 -1 (-700 2550)(-700 2600);
WIRE 17 -1 (-700 2600)(-700 2650);
WIRE 17 -1 (-700 2650)(-700 2700);
WIRE 17 -1 (-700 2700)(-700 2750);
WIRE 17 -1 (-700 2750)(-700 2800);
WIRE 17 -1 (-700 2800)(-700 2850);
WIRE 17 -1 (-700 2850)(-700 2900);
WIRE 17 -1 (-700 2900)(-700 2950);
WIRE 17 -1 (-700 2950)(-700 3000);
WIRE 17 -1 (-700 3000)(-700 3050);
WIRE 17 -1 (-700 3050)(-700 3100);
WIRE 17 -1 (-700 3100)(-700 3150);
WIRE 17 -1 (-700 3150)(-700 3200);
WIRE 17 -1 (-700 3200)(-700 3250);
WIRE 17 -1 (-700 3250)(-700 3300);
WIRE 17 -1 (-700 3300)(-700 3350);
WIRE 17 -1 (-700 3350)(-700 3400);
WIRE 17 -1 (-700 3400)(-700 3450);
WIRE 17 -1 (-700 3450)(-700 3500);
WIRE 17 -1 (-700 3500)(-700 3550);
WIRE 17 -1 (-700 3550)(-700 3600);
WIRE 17 -1 (-700 3600)(-700 3650);
WIRE 17 -1 (-700 3650)(-700 3700);
WIRE 17 -1 (-700 3700)(-700 3750);
WIRE 17 -1 (-700 3750)(-700 3800);
WIRE 17 -1 (-700 3800)(-700 3850);
WIRE 17 -1 (-1625 3850)(-700 3850);
FORCEPROP 2 LAST SIG_NAME M_H_CPU1_SA_DQ<31:0>
J 0
(-1485 3860);
DISPLAY 0.680851 (-1485 3860);
PAINT WHITE (-1485 3860);
WIRE 17 -1 (-700 -250)(-700 -200);
WIRE 17 -1 (-1625 -200)(-700 -200);
FORCEPROP 2 LAST SIG_NAME M_H_CPU1_CLK_DP<1:0>
J 0
(-1485 -190);
DISPLAY 0.680851 (-1485 -190);
PAINT WHITE (-1485 -190);
WIRE 17 -1 (-700 -350)(-700 -300);
WIRE 17 -1 (-1625 -300)(-700 -300);
FORCEPROP 2 LAST SIG_NAME M_H_CPU1_CLK_DN<1:0>
J 0
(-1485 -290);
DISPLAY 0.680851 (-1485 -290);
PAINT WHITE (-1485 -290);
WIRE 16 -1 (-600 -325)(-150 -325);
WIRE 16 -1 (-600 -375)(-150 -375);
WIRE 16 -1 (-600 -225)(-150 -225);
WIRE 16 -1 (-600 -275)(-150 -275);
WIRE 16 -1 (-600 3825)(-150 3825);
WIRE 16 -1 (-600 3775)(-150 3775);
WIRE 16 -1 (-600 3725)(-150 3725);
WIRE 16 -1 (-600 3675)(-150 3675);
WIRE 16 -1 (-600 3625)(-150 3625);
WIRE 16 -1 (-600 3575)(-150 3575);
WIRE 16 -1 (-600 3525)(-150 3525);
WIRE 16 -1 (-600 3475)(-150 3475);
WIRE 16 -1 (-600 3425)(-150 3425);
WIRE 16 -1 (-600 3375)(-150 3375);
WIRE 16 -1 (-600 3325)(-150 3325);
WIRE 16 -1 (-600 3275)(-150 3275);
WIRE 16 -1 (-600 3225)(-150 3225);
WIRE 16 -1 (-600 3175)(-150 3175);
WIRE 16 -1 (-600 3125)(-150 3125);
WIRE 16 -1 (-600 3075)(-150 3075);
WIRE 16 -1 (-600 3025)(-150 3025);
WIRE 16 -1 (-600 2975)(-150 2975);
WIRE 16 -1 (-600 2925)(-150 2925);
WIRE 16 -1 (-600 2875)(-150 2875);
WIRE 16 -1 (-600 2825)(-150 2825);
WIRE 16 -1 (-600 2775)(-150 2775);
WIRE 16 -1 (-600 2725)(-150 2725);
WIRE 16 -1 (-600 2675)(-150 2675);
WIRE 16 -1 (-600 2625)(-150 2625);
WIRE 16 -1 (-600 2575)(-150 2575);
WIRE 16 -1 (-600 2525)(-150 2525);
WIRE 16 -1 (-600 2475)(-150 2475);
WIRE 16 -1 (-600 2425)(-150 2425);
WIRE 16 -1 (-600 2375)(-150 2375);
WIRE 16 -1 (-600 2325)(-150 2325);
WIRE 16 -1 (-600 2275)(-150 2275);
WIRE 16 -1 (-600 2225)(-150 2225);
WIRE 16 -1 (-600 2175)(-150 2175);
WIRE 16 -1 (-600 2125)(-150 2125);
WIRE 16 -1 (-600 2075)(-150 2075);
WIRE 16 -1 (-600 2025)(-150 2025);
WIRE 16 -1 (-600 1975)(-150 1975);
WIRE 16 -1 (-600 1925)(-150 1925);
WIRE 16 -1 (-600 1875)(-150 1875);
WIRE 16 -1 (-600 1825)(-150 1825);
WIRE 16 -1 (-600 1775)(-150 1775);
WIRE 16 -1 (-600 1725)(-150 1725);
WIRE 16 -1 (-600 1675)(-150 1675);
WIRE 16 -1 (-600 1625)(-150 1625);
WIRE 16 -1 (-600 1575)(-150 1575);
WIRE 16 -1 (-600 1525)(-150 1525);
WIRE 16 -1 (-600 1475)(-150 1475);
WIRE 16 -1 (-600 1425)(-150 1425);
WIRE 16 -1 (-600 1375)(-150 1375);
WIRE 16 -1 (-600 1325)(-150 1325);
WIRE 16 -1 (-600 1275)(-150 1275);
WIRE 16 -1 (-600 1225)(-150 1225);
WIRE 16 -1 (-600 1175)(-150 1175);
WIRE 16 -1 (-600 1125)(-150 1125);
WIRE 16 -1 (-600 1075)(-150 1075);
WIRE 16 -1 (-600 1025)(-150 1025);
WIRE 16 -1 (-600 975)(-150 975);
WIRE 16 -1 (-600 925)(-150 925);
WIRE 16 -1 (-600 875)(-150 875);
WIRE 16 -1 (-600 825)(-150 825);
WIRE 16 -1 (-600 775)(-150 775);
WIRE 16 -1 (-600 725)(-150 725);
WIRE 16 -1 (-600 675)(-150 675);
WIRE 16 -1 (-600 625)(-150 625);
WIRE 16 -1 (-600 575)(-150 575);
WIRE 16 -1 (-600 525)(-150 525);
WIRE 16 -1 (-600 475)(-150 475);
WIRE 16 -1 (-600 425)(-150 425);
WIRE 16 -1 (-600 375)(-150 375);
WIRE 16 -1 (-600 325)(-150 325);
WIRE 16 -1 (-600 275)(-150 275);
WIRE 16 -1 (-600 225)(-150 225);
WIRE 16 -1 (-600 175)(-150 175);
WIRE 16 -1 (-600 125)(-150 125);
WIRE 16 -1 (-600 75)(-150 75);
WIRE 16 -1 (-600 25)(-150 25);
WIRE 16 -1 (-600 -25)(-150 -25);
WIRE 16 -1 (-600 -75)(-150 -75);
WIRE 16 -1 (-600 -125)(-150 -125);
WIRE 16 -1 (3825 675)(2300 675);
FORCEPROP 2 LAST SIG_NAME M_H_CPU1_SB_PAR
J 0
(2934 684);
DISPLAY 0.680851 (2934 684);
PAINT WHITE (2934 684);
WIRE 16 -1 (2300 2225)(2725 2225);
WIRE 16 -1 (2300 2275)(2725 2275);
WIRE 16 -1 (2300 2325)(2725 2325);
WIRE 16 -1 (2300 2375)(2725 2375);
WIRE 16 -1 (2300 2425)(2725 2425);
WIRE 16 -1 (2300 2475)(2725 2475);
WIRE 16 -1 (2300 2525)(2725 2525);
WIRE 16 -1 (2300 2575)(2725 2575);
WIRE 16 -1 (2300 2625)(2725 2625);
WIRE 16 -1 (2300 2675)(2725 2675);
WIRE 16 -1 (2300 1675)(2725 1675);
WIRE 16 -1 (2300 1725)(2725 1725);
WIRE 16 -1 (2300 1775)(2725 1775);
WIRE 16 -1 (2300 1825)(2725 1825);
WIRE 16 -1 (2300 1875)(2725 1875);
WIRE 16 -1 (2300 1925)(2725 1925);
WIRE 16 -1 (2300 1975)(2725 1975);
WIRE 16 -1 (2300 2025)(2725 2025);
WIRE 16 -1 (2300 2075)(2725 2075);
WIRE 16 -1 (2300 2125)(2725 2125);
WIRE 16 -1 (2300 75)(2725 75);
WIRE 16 -1 (2300 125)(2725 125);
WIRE 16 -1 (2300 175)(2725 175);
WIRE 16 -1 (2300 225)(2725 225);
WIRE 16 -1 (2300 725)(2725 725);
WIRE 16 -1 (2300 775)(2725 775);
WIRE 16 -1 (2300 825)(2725 825);
WIRE 16 -1 (2300 875)(2725 875);
WIRE 16 -1 (2300 925)(2725 925);
WIRE 16 -1 (2300 975)(2725 975);
WIRE 16 -1 (2300 1025)(2725 1025);
WIRE 16 -1 (3825 1175)(2300 1175);
FORCEPROP 2 LAST SIG_NAME M_H_CPU1_SA_PAR
J 0
(2934 1184);
DISPLAY 0.680851 (2934 1184);
PAINT WHITE (2934 1184);
WIRE 16 -1 (2300 3375)(2725 3375);
WIRE 16 -1 (2300 3425)(2725 3425);
WIRE 16 -1 (2300 3475)(2725 3475);
WIRE 16 -1 (2300 3525)(2725 3525);
WIRE 16 -1 (2300 3575)(2725 3575);
WIRE 16 -1 (2300 3625)(2725 3625);
WIRE 16 -1 (2300 3675)(2725 3675);
WIRE 16 -1 (2300 3725)(2725 3725);
WIRE 16 -1 (2300 3775)(2725 3775);
WIRE 16 -1 (2300 3825)(2725 3825);
WIRE 16 -1 (2300 2825)(2725 2825);
WIRE 16 -1 (2300 2875)(2725 2875);
WIRE 16 -1 (2300 2925)(2725 2925);
WIRE 16 -1 (2300 2975)(2725 2975);
WIRE 16 -1 (2300 3025)(2725 3025);
WIRE 16 -1 (2300 3075)(2725 3075);
WIRE 16 -1 (2300 3125)(2725 3125);
WIRE 16 -1 (2300 3175)(2725 3175);
WIRE 16 -1 (2300 3225)(2725 3225);
WIRE 16 -1 (2300 3275)(2725 3275);
WIRE 16 -1 (2300 375)(2725 375);
WIRE 16 -1 (2300 425)(2725 425);
WIRE 16 -1 (2300 475)(2725 475);
WIRE 16 -1 (2300 525)(2725 525);
WIRE 16 -1 (2300 1225)(2725 1225);
WIRE 16 -1 (2300 1275)(2725 1275);
WIRE 16 -1 (2300 1325)(2725 1325);
WIRE 16 -1 (2300 1375)(2725 1375);
WIRE 16 -1 (2300 1425)(2725 1425);
WIRE 16 -1 (2300 1475)(2725 1475);
WIRE 16 -1 (2300 1525)(2725 1525);
WIRE 16 -1 (3825 -275)(2300 -275);
FORCEPROP 2 LAST SIG_NAME M_H_CPU1_SB_RSP<0>
J 0
(2934 -266);
DISPLAY 0.680851 (2934 -266);
PAINT WHITE (2934 -266);
WIRE 16 -1 (3825 -225)(2300 -225);
FORCEPROP 2 LAST SIG_NAME M_H_CPU1_SB_RSP<1>
J 0
(2934 -216);
DISPLAY 0.680851 (2934 -216);
PAINT WHITE (2934 -216);
WIRE 16 -1 (3825 -125)(2300 -125);
FORCEPROP 2 LAST SIG_NAME M_H_CPU1_SA_RSP<0>
J 0
(2934 -116);
DISPLAY 0.680851 (2934 -116);
PAINT WHITE (2934 -116);
WIRE 16 -1 (3825 -75)(2300 -75);
FORCEPROP 2 LAST SIG_NAME M_H_CPU1_SA_RSP<1>
J 0
(2934 -66);
DISPLAY 0.680851 (2934 -66);
PAINT WHITE (2934 -66);
WIRE 16 -1 (3825 -375)(2300 -375);
FORCEPROP 2 LAST SIG_NAME M_H_CPU1_ALERT_N
J 0
(2934 -366);
DISPLAY 0.680851 (2934 -366);
PAINT WHITE (2934 -366);
QUIT
